# BARRELEYE_G2-MB-PVT-X04-HW-BOM-X26_20180122_Final.xls.xlsx — PWA BOM (bom)
| FOXCONN TECHNOLOGY GROUP |  |  |  |  |  |  |  |  |  |  |  |  |  |  |  |  |  |  |  |
| BILL OF MATERIAL |  |  |  |  |  |  |  |  |  |  |  |  |  |  |  |  |  |  |  |
| REV OF  BOM | X26 | CUSTOMER |  | RACKSPACE |  | CUSTOMER P/N |  | PWA P/N： | PWA DESCRIPTION |  |  |  | PRODUCT CODE |  |  | PWA  REV | X04 | DATE | 43122 |
| Sourcing (Single/Sole/Multi) | Critical Commodity (Y or N) | Component Class (1, 2, other) | Customer PSL (Y or N) | Line Item | Item Number | Foxconn P/N | Customer P/N | Part Description | Manufacturer  Full Name | Manufacturer  Part Number | Qty | RoHS Status | Location | CC Qual Build: | Qual by (Customer / ODM ?) | The Date of Change Part or Add 2nd Source | Configuration Identifier | Customer Comments | ODM Comments |
| Multi |  |  |  | 1 | 1 | 0101FBQ00-000-G |  | PCB,Zaius-MB PVT-X04,OSP,Gre,22L,22.20*13.00,G | GOLD CIRCUIT ELECTRONICS LTD. | 0101FBQ00-000-G | 1 | G | PCB |  |  |  |  |  |  |
|  |  |  |  |  | 1 | 0101FBQ00-000-G |  | PCB,Zaius-MB PVT-X04,OSP,Gre,22L,22.20*13.00,G | ZHUHAI FOUNDER PRINTED CIRCUIT BOARD_x0008_HK	 DEVELOPMENT LIMITED | 0101FBQ00-000-G |  | G |  |  |  |  |  |  |  |
| Multi | N | ND | Y(2) | 2 | 2 | 890100800-024-G | - | Battery,PANASONIC,CR-2032L/BE,Lithium,3V,225mAH,G | PANASONIC INDUSTRIAL CO.,LTD. | CR-2032L/BE | 1 | G | BAT1 |  |  |  |  |  |  |
|  |  |  |  |  | 2 | 6032-101-501 |  | Battery,VARTA,CR-2032,Lithium,3V,230mAH,G | Varta | 6032-101-501 |  | G |  |  |  |  |  |  |  |
| Multi | ND |  | N | 3 | 3 | 622202200-022-G |  | SPET CAP,220uF,+/-20%,10V,105℃,G,SMD2816,ESR<=40mOhm | SANYO ELECTRIC CO., LTD. | 10TPB220ML | 6 | G | CE1,CE4,CE5,CE6,CE33,CE34 |  |  |  |  |  |  |
|  |  |  |  |  | 3 | 622202201-025-G |  | SPET CAP,220uF,+/-20%,10V,105℃,G,SMD2816,ESR<=40mOhm | KEMET ELECTRONICS CORPORATION | T520D227M010ATE040 |  | G |  |  |  |  |  |  |  |
| Multi | Y |  | N | 4 | 4 | 62120FL00-022-G |  | SPEA CAP,100uF,+/-20%,16V,105℃,G,SMD6.3*5.9,ESR<=24mOhm | SANYO ELECTRIC CO., LTD. | 16SVPC100M | 4 | G | CE17,CE18,CE19,CE20 |  |  |  |  |  |  |
|  |  |  |  |  | 4 | 62120CB00-025-G |  | ECAP,Solid Polymer Electrolytic Aluminium Capacitor (SPEA),Low ESR(LESR),100uF,+/-20%,16V,105_x0003_,25mOhm,SMD,6.3*5.7,G | KEMET ELECTRONICS CORPORATION | A765EB107M1CLAE025 |  | G |  |  |  |  |  |  |  |
| Single | Y | ND | Y(5) | 5 | 5 | 62120BE00-015-G |  | SP-CAP,100uF,+/-20%,16V,105℃,G,SMD2816,ESR<=12mOhm | MURATA ELEC. NORTH AMERICA | ECASD91C107M012K01 | 10 | G | CE21,CE22,CE23,CE24,CE25,CE26,CE27,CE28,CE29,CE30 |  |  |  |  |  |  |
| Multi | Y | ND | Y(3) | 6 | 6 | 62011U701-015-G | - | CAP,10nF,+/-10%,X7R,6.3V,G,SMD0402 | MURATA ELEC. NORTH AMERICA | GRM155R70J103K | 43 | G | C5,C6,C9,C14,C15,C189,C190,C730,C731,C734,C737,C738,C905,C906,C1513,C1628,C1629,C1630,C1631,C1632,C1633,C1634,C1635,C1636,C1637,C1638,C1639,C1640,C1641,C1642,C1643,C1644,C1667,C1730,C1731,C1732,C1733,C1742,C1743,C1744,C1745,C2048,C2087 |  |  |  |  |  |  |
|  |  |  |  |  | 6 | 62011U700-012-G |  | CAP,10nF,+/-10%,X7R,6.3V,G,SMD0402 | WALSIN TECHNOLOGY CORPORATION | 0402B103K6R3CT |  | G |  |  |  |  |  |  |  |
|  |  |  |  |  | 6 | 62011U700-023-G |  | CAP,10nF,+/-10%,X7R,6.3V,G,SMD0402 | TAIYO ELECTRIC IND.CO.LTD | JMK105B7103KV-F |  | G |  |  |  |  |  |  |  |
| Multi | ND |  | Y(3) | 7 | 7 | 620106200-015-G |  | CAP,10nF,+/-10%,X7R,16V,G,SMD0402 | MURATA ELEC. NORTH AMERICA | GRM155R71C103KA01D | 38 | G | PUAC2,PSAC2,PRAC2,PQAC2,PPAC2,PIAC2,PFAC2,PEAC2,PANC7,PBNC8,PBNC15,PANC15,C33,C34,C698,C700,C701,C702,C705,C750,C1714,C1718,C1722,C1726,C2026,C2064,C2065,C2085,C2086,C2088,C2089,C2090,C2091,C2093,C2094,C2098,C2115,C2116 |  |  |  |  |  |  |
|  |  |  |  |  | 7 | 620106200-012-G |  | CAP,10nF,+/-10%,X7R,16V,G,SMD0402 | WALSIN TECHNOLOGY CORPORATION | 0402B103K160CT |  | G |  |  |  |  |  |  |  |
|  |  |  |  |  | 7 | 620106200-026-G |  | CAP,10nF,+/-10%,X7R,16V,G,SMD0402 | SAMSUNG SEMICONDUCTOR | CL05B103KO5NNNC |  | G |  |  |  |  |  |  |  |
|  |  |  |  |  | 7 | 620106200-023-G |  | CAP,10nF,+/-10%,X7R,16V,G,SMD0402 | TAIYO ELECTRIC IND.CO.LTD | EMK105B7103KV-F |  | G |  |  |  |  |  |  |  |
| Multi | ND | ND | Y(3) | 8 | 8 | 620103700-015-G | - | CAP,100nF,+/-10%,X7R,10V,G,SMD0402 | MURATA ELEC. NORTH AMERICA | GRM155R71A104K | 174 | G | PHAC5,PUAC10,PSLC10,PSIC10,PSFC10,PSEC10,PSDC10,PSAC10,PRAC10,PQAC10,PPAC10,PIAC10,PFAC10,PEEC10,PEDC10,PEAC10,C35,C84,C85,C86,C87,C88,C89,C90,C91,C92,C93,C94,C98,C99,C100,C101,C102,C103,C104,C105,C106,C107,C108,C687,C688,C691,C692,C693,C695,C696,C706,C707,C708,C709,C710,C711,C712,C713,C714,C715,C716,C717,C718,C720,C721,C722,C723,C724,C725,C751,C793,C801,C802,C803,C804,C805,C806,C807,C808,C809,C810,C815,C816,C817,C818,C819,C820,C821,C822,C823,C824,C1497,C1498,C1503,C1504,C1691,C1692,C1693,C1694,C1699,C1700,C1701,C1702,C2000,C2001,C2002,C2003,C2021,C2022,C2023,C2024,C2025,C2027,C2034,C2036,C2037,C2038,C2039,C2040,C2042,C2043,C2044,C2045,C2046,C2049,C2050,C2051,C2052,C2053,C2054,C2055,C2056,C2057,C2058,C2059,C2060,C2061,C2062,C2067,C2068,C2073,C2075,C2077,C2078,C2079,C2080,C2083,C2084,C2095,C2096,C2099,C2100,C2101,C2102,C2103,C2104,C2105,C2106,C2117,C2118,C2119,C2123,C2125,C2126,C2127,C2128,C2130,C2133,C2134,C2135,C2142,C2144,C2157,C2158,C2159,C2160,C2161,C2186 |  |  |  |  |  |  |
|  |  |  |  |  | 8 | 620103700-012-G |  | CAP,0.1uF,+/-10%,X7R,10V,G,SMD0402 | WALSIN TECHNOLOGY CORPORATION | 0402B104K100CT |  | G |  |  |  |  |  |  |  |
|  |  |  |  |  | 8 | 620103700-023-G |  | CAP,100nF,+/-10%,X7R,10V,G,SMD0402 | TAIYO ELECTRIC IND.CO.LTD | LMK105B7104KV-F |  | G |  |  |  |  |  |  |  |
|  |  |  |  |  | 8 | 620103700-026-G |  | CAP,100nF,+/-10%,X7R,10V,G,SMD0402 | SAMSUNG SEMICONDUCTOR | CL05B104KP5NNNC |  | G |  |  |  |  |  |  |  |
| Multi | ND | ND | Y(1) | 9 | 9 | 62010P501-015-G | - | CAP,1nF,+/-10%,X7R,16V,G,SMD0402 | MURATA ELEC. NORTH AMERICA | GRM155R71C102KA01D | 59 | G | C36,C191,C193,C195,C197,C207,C208,C217,C218,C219,C220,C221,C222,C223,C315,C317,C319,C321,C439,C441,C443,C445,C563,C565,C567,C569,C699,C703,C704,C749,C752,C907,C909,C911,C913,C1031,C1033,C1035,C1037,C1155,C1157,C1159,C1161,C1279,C1281,C1283,C1285,C1514,C1517,C1519,C1716,C1720,C1724,C1728,C1947,C1948,C2047,C2124,C2187 |  |  |  |  |  |  |
|  |  |  |  |  | 9 | 62010P500-026-G |  | CAP,1nF,+/-10%,X7R,16V,G,SMD0402 | SAMSUNG SEMICONDUCTOR | CL05B102KO5NNNC |  | G |  |  |  |  |  |  |  |
|  |  |  |  |  | 9 | 62010P500-023-G |  | CAP,1nF,+/-10%,X7R,16V,G,SMD0402 | TAIYO ELECTRIC IND.CO.LTD | EMK105B7102KV-F |  | G |  |  |  |  |  |  |  |
| Multi | ND | ND | Y(4) | 10 | 10 | 62011SJ00-026-G | - | CAP,470nF,+/-10%,X7R,6.3V,G,SMD0402 | SAMSUNG SEMICONDUCTOR | CL05B474KQ5NNNC | 160 | G | C38,C39,C47,C78,C95,C96,C137,C141,C143,C145,C148,C150,C183,C185,C186,C188,C236,C241,C242,C243,C244,C251,C252,C253,C254,C269,C270,C271,C272,C287,C288,C289,C290,C365,C366,C367,C368,C375,C376,C377,C378,C393,C394,C395,C396,C411,C412,C413,C414,C489,C490,C491,C492,C499,C500,C501,C502,C517,C518,C519,C520,C535,C536,C537,C538,C613,C614,C615,C616,C623,C624,C625,C626,C641,C642,C643,C644,C659,C660,C661,C662,C766,C768,C786,C791,C792,C811,C847,C851,C852,C853,C854,C857,C858,C866,C902,C957,C958,C959,C960,C967,C968,C969,C970,C985,C986,C987,C988,C1003,C1004,C1005,C1006,C1081,C1082,C1083,C1084,C1091,C1092,C1093,C1094,C1109,C1110,C1111,C1112,C1127,C1128,C1129,C1130,C1205,C1206,C1207,C1208,C1215,C1216,C1217,C1218,C1233,C1234,C1235,C1236,C1251,C1252,C1253,C1254,C1329,C1330,C1331,C1332,C1339,C1340,C1341,C1342,C1357,C1358,C1359,C1360,C1375,C1376,C1377,C1378 |  |  |  |  |  |  |
|  |  |  |  |  | 10 | 62011SJ00-023-G |  | CAP,470nF,+/-10%,X7R,6.3V,G,SMD0402 | TAIYO ELECTRIC IND.CO.LTD | JMK105B7474KV-F |  | G |  |  |  |  |  |  |  |
| Multi | Y | ND | Y(1) | 11 | 11 | 62012WD00-015-G | - | CAP,4.7uF,+/-20%,X6S,6.3V,G,SMD0402 | MURATA ELEC. NORTH AMERICA | GRM155C80J475MEAAD | 20 | G | C40,C53,C56,C62,C65,C73,C74,C147,C689,C690,C694,C764,C767,C775,C777,C787,C788,C790,C860,C2166 |  |  |  |  |  |  |
|  |  |  |  |  | 11 | 62012WD00-023-G |  | CAP,4.7uF,+/-20%,X6S,6.3V,G,SMD0402 | TAIYO ELECTRIC IND.CO.LTD | JMK105BC6475MV-F |  | G |  |  |  |  |  |  |  |
| Multi | ND | ND | N | 12 | 12 | 62012NU00-015-G | - | CAP,1uF,+/-10%,X7R,6.3V,G,SMD0402 | MURATA ELEC. NORTH AMERICA | GRM155R70J105KA12D | 109 | G | C41,C42,C43,C44,C45,C48,C49,C50,C51,C52,C54,C55,C57,C58,C59,C61,C64,C67,C68,C71,C72,C134,C136,C146,C149,C159,C160,C169,C170,C181,C199,C200,C201,C228,C697,C754,C755,C756,C758,C759,C760,C761,C763,C765,C769,C770,C771,C772,C773,C776,C778,C779,C780,C782,C783,C784,C789,C799,C848,C849,C855,C875,C876,C885,C886,C903,C916,C917,C1475,C1482,C1483,C1500,C1501,C1505,C1506,C1507,C1508,C1509,C1510,C1512,C1572,C1573,C1574,C1575,C1578,C1579,C1580,C1581,C1582,C1583,C1586,C1587,C1588,C1589,C1590,C1591,C1593,C1594,C1595,C1599,C1602,C1605,C1650,C1748,C1833,C2072,C2074,C2076,C2143 |  |  |  |  |  |  |
|  |  |  |  |  | 12 | 62012NU00-026-G |  | CAP,1uF,+/-10%,X7R,6.3V,G,SMD0402 | SAMSUNG SEMICONDUCTOR | CL05B105KQ5NQNC |  | G |  |  |  |  |  |  |  |
| Multi | ND |  | Y(3) | 13 | 13 | 62012P100-015-G |  | CAP,2.2uF,+/-20%,X7S,10V,G,SMD0402 | MURATA ELEC. NORTH AMERICA | GRM155C71A225M | 28 | G | PSTC5,PSLC5,PSFC5,PSEC5,PSDC5,PQPC5,PFRC5,PEEC5,PEDC5,C46,C63,C69,C79,C142,C144,C157,C167,C226,C234,C774,C781,C785,C813,C856,C864,C873,C883,C2011 |  |  |  |  |  |  |
|  |  |  |  |  | 13 | 62012P100-012-G |  | CAP,2.2uF,+/-20%,X7S,10V,G,SMD0402 | WALSIN TECHNOLOGY CORPORATION | 0402A225M100CT |  | G |  |  |  |  |  |  |  |
| Multi | Y | 2 | Y(3) | 14 | 14 | 62011DF01-015-G | - | CAP,220nF,+/-10%,X7R,16V,G,SMD0402 | MURATA ELEC. NORTH AMERICA | GRM155R71C224K | 283 | G | C66,C70,C75,C76,C77,C81,C82,C97,C109,C110,C111,C112,C113,C114,C115,C116,C117,C118,C119,C120,C121,C122,C123,C124,C125,C126,C127,C128,C129,C130,C131,C132,C133,C135,C139,C140,C151,C152,C153,C154,C155,C156,C161,C162,C163,C164,C165,C166,C171,C172,C173,C174,C175,C176,C177,C178,C179,C180,C187,C203,C206,C224,C233,C235,C245,C762,C796,C797,C798,C800,C825,C826,C827,C828,C829,C830,C831,C832,C833,C834,C835,C836,C837,C838,C839,C840,C841,C842,C843,C844,C845,C846,C850,C859,C861,C862,C863,C865,C867,C868,C869,C870,C871,C872,C877,C878,C879,C880,C881,C882,C887,C888,C889,C890,C891,C892,C893,C894,C895,C896,C898,C901,C915,C1753,C1754,C1755,C1756,C1757,C1758,C1759,C1760,C1761,C1762,C1763,C1764,C1765,C1766,C1767,C1768,C1782,C1783,C1784,C1785,C1788,C1789,C1790,C1791,C1792,C1794,C1798,C1799,C1800,C1801,C1802,C1803,C1805,C1806,C1807,C1808,C1809,C1811,C1812,C1813,C1814,C1815,C1819,C1820,C1821,C1822,C1823,C1824,C1826,C1828,C1829,C1830,C1831,C1834,C1835,C1836,C1837,C1838,C1843,C1844,C1845,C1846,C1847,C1848,C1849,C1851,C1852,C1853,C1854,C1855,C1856,C1858,C1859,C1860,C1861,C1862,C1866,C1867,C1868,C1869,C1872,C1873,C1874,C1877,C1878,C1879,C1880,C1881,C1882,C1884,C1888,C1889,C1890,C1891,C1892,C1893,C1895,C1896,C1897,C1898,C1899,C1901,C1902,C1903,C1904,C1905,C1909,C1910,C1911,C1912,C1913,C1914,C1917,C1918,C1919,C1920,C1921,C1922,C1923,C1924,C1925,C1926,C1927,C1928,C1929,C1930,C1931,C1932,C1952,C1953,C1954,C1955,C1956,C1957,C1962,C1963,C1964,C1965,C1966,C1967,C1968,C1969,C1974,C1975,C1984,C1985,C1986,C1987,C1988,C1989,C1990,C1991,C1992,C1993,C1994,C1995,C1996,C1997,C1998,C1999 |  |  |  |  |  |  |
|  |  |  |  |  | 14 | 62011DF00-026-G |  | CAP,220nF,+/-10%,X7R,16V,G,SMD0402 | SAMSUNG SEMICONDUCTOR | CL05B224KO5NNNC |  | G |  |  |  |  |  |  |  |
|  |  |  |  |  | 14 | 62011DF00-023-G |  | CAP,220nF,+/-10%,X7R,16V,G,SMD0402 | TAIYO ELECTRIC IND.CO.LTD | EMK105B7224KV-FR |  | G |  |  |  |  |  |  |  |
| Multi | N |  | Y(3) | 15 | 15 | 62012GF00-015-G |  | CAP,22uF,+/-20%,X6S,6.3V,G,SMD0603 | MURATA ELEC. NORTH AMERICA | GRM188C80J226M | 16 | G | PSPC2,PIPC2,PFPC2,PEPC2,PSPC3,PIPC3,PFPC3,PEPC3,C158,C168,C874,C884,PSPC3000,PIPC3000,PFPC3000,PEPC3000 |  |  |  |  |  |  |
|  |  |  |  |  | 15 | 62012GF00-023-G |  | CAP,22uF,+/-20%,X6S,6.3V,G,SMD0603 | TAIYO ELECTRIC IND.CO.LTD | JDK107BC6226MA-T |  | G |  |  |  |  |  |  |  |
| Multi | N | ND | Y(3) | 16 | 16 | 62012H100-015-G | - | CAP,10uF,+/-20%,X6S,10V,G,SMD0603 | MURATA ELEC. NORTH AMERICA | GRM188C81A106M | 11 | G | PSTC16,PFRC16,C182,C225,C273,C812,C2147,C2148,C2149,C2150,C2151 |  |  |  |  |  |  |
|  |  |  |  |  | 16 | 62012H100-023-G |  | CAP,10uF,+/-20%,X6S,10V,G,SMD0603 | TAIYO ELECTRIC IND.CO.LTD | LMK107BC6106MA-T |  | G |  |  |  |  |  |  |  |
|  |  |  |  |  | 16 | 62012H100-026-G |  | CAP,10uF,+/-20%,X6S,10V,G,SMD0603 | SAMSUNG SEMICONDUCTOR | CL10X106MP8NRNC |  | G |  |  |  |  |  |  |  |
| Multi | Y | 2 | Y(3) | 17 | 17 | 620101T02-015-G | - | CAP,100nF,+/-10%,X7R,16V,G,SMD0402 | MURATA ELEC. NORTH AMERICA | GRM155R71C104K | 233 | G | PSPC1,PIPC1,PFPC1,PEPC1,PSTC10,PQPC10,PFRC10,PETC10,PERC10,PBNC16,PANC16,PBNC17,PANC17,PALC36,PALC41,PALC44,PBLC57,PBLC61,PBLC64,C192,C194,C196,C198,C316,C318,C320,C322,C440,C442,C444,C446,PBFC500,PBEC500,PAFC500,PAEC500,C564,C566,C568,C570,PBMC600,PBAC600,PAMC600,PAAC600,C908,C910,C912,C914,C1032,C1034,C1036,C1038,C1156,C1158,C1160,C1162,C1280,C1282,C1284,C1286,C1403,C1404,C1405,C1406,C1407,C1408,C1409,C1410,C1411,C1412,C1413,C1414,C1415,C1416,C1417,C1418,C1419,C1422,C1423,C1425,C1426,C1428,C1429,C1430,C1431,C1432,C1433,C1434,C1435,C1436,C1437,C1438,C1441,C1442,C1443,C1444,C1445,C1446,C1449,C1450,C1452,C1453,C1454,C1457,C1460,C1461,C1462,C1465,C1467,C1469,C1471,C1472,C1480,C1481,C1484,C1487,C1488,C1490,C1491,C1493,C1494,C1496,C1515,C1516,C1518,C1520,C1521,C1522,C1524,C1526,C1527,C1528,C1529,C1530,C1531,C1534,C1535,C1536,C1537,C1538,C1539,C1540,C1543,C1544,C1545,C1552,C1561,C1562,C1568,C1569,C1570,C1571,C1576,C1597,C1600,C1603,C1606,C1608,C1609,C1610,C1611,C1612,C1613,C1616,C1617,C1618,C1619,C1620,C1621,C1622,C1624,C1625,C1626,C1627,C1645,C1646,C1647,C1648,C1649,C1651,C1652,C1677,C1678,C1713,C1715,C1719,C1723,C1727,C1738,C1740,C1749,C1750,C1787,C1796,C1797,C1841,C1842,C1876,C1886,C1887,C1940,C1941,C1943,C1946,C1949,C1951,C1959,C1960,C1961,C1977,C1978,C1979,C1980,C1981,C1982,C1983,C2012,C2029,C2070,C2107,C2108,C2109,C2112,C2131,C2132,C2152,C2155,C2156,C2163,C2164,C2165,C2167,C2181,PSRC3016 |  |  |  |  |  |  |
|  |  |  |  |  | 17 | 620101T00-012-G |  | CAP,100nF,+/-10%,X7R,16V,G,SMD0402 | WALSIN TECHNOLOGY CORPORATION | 0402B104K160CT |  | G |  |  |  |  |  |  |  |
|  |  |  |  |  | 17 | 620101T00-026-G |  | CAP,100nF,+/-10%,X7R,16V,G,SMD0402 | SAMSUNG SEMICONDUCTOR | CL05B104KO5NNNC |  | G |  |  |  |  |  |  |  |
|  |  |  |  |  | 17 | 620101T00-015-G |  | CAP,100nF,+/-10%,X7R,16V,G,SMD0402 | MURATA ELEC. NORTH AMERICA | GRM155R71C104KA88D |  | G |  |  |  |  |  |  |  |
| Multi | Y | ND | Y(3) | 18 | 18 | 62011KG00-015-G | - | CAP,100nF,+/-5%,X7R,10V,G,SMD0402 | MURATA ELEC. NORTH AMERICA | GRM155R71A104JA01D | 67 | G | C209,C210,C211,C212,C213,C214,C215,C216,C227,C333,C334,C335,C336,C337,C338,C339,C340,C457,C458,C459,C460,C461,C462,C463,C464,C581,C582,C583,C584,C585,C586,C587,C588,C925,C926,C927,C928,C929,C930,C931,C932,C1049,C1050,C1051,C1052,C1053,C1054,C1055,C1056,C1173,C1174,C1175,C1176,C1177,C1178,C1179,C1180,C1297,C1298,C1299,C1300,C1301,C1302,C1303,C1304,C1532,C2009 |  |  |  |  |  |  |
|  |  |  |  |  | 18 | 62011KG00-012-G |  | CAP,100nF,+/-5%,X7R,10V,G,SMD0402 | WALSIN TECHNOLOGY CORPORATION | 0402B104J100CT |  | G |  |  |  |  |  |  |  |
|  |  |  |  |  | 18 | 62011KG00-026-G |  | CAP,100nF,+/-5%,X7R,10V,G,SMD0402 | SAMSUNG SEMICONDUCTOR | CL05B104JP5NNNC |  | G |  |  |  |  |  |  |  |
| Multi | ND | ND | Y(1) | 19 | 19 | 620135Y00-015-G | - | CAP,2.2uF,+/-20%,X6S,10V,G,SMD0402 | MURATA ELEC. NORTH AMERICA | GRM155C81A225ME15D | 130 | G | PBNC9,PANC9,C237,C238,C239,C240,C247,C248,C249,C250,C265,C266,C267,C268,C283,C284,C285,C286,C361,C362,C363,C364,C371,C372,C373,C374,C389,C390,C391,C392,C407,C408,C409,C410,C485,C486,C487,C488,C495,C496,C497,C498,C513,C514,C515,C516,C531,C532,C533,C534,C609,C610,C611,C612,C619,C620,C621,C622,C637,C638,C639,C640,C655,C656,C657,C658,C953,C954,C955,C956,C963,C964,C965,C966,C981,C982,C983,C984,C999,C1000,C1001,C1002,C1077,C1078,C1079,C1080,C1087,C1088,C1089,C1090,C1105,C1106,C1107,C1108,C1123,C1124,C1125,C1126,C1201,C1202,C1203,C1204,C1211,C1212,C1213,C1214,C1229,C1230,C1231,C1232,C1247,C1248,C1249,C1250,C1325,C1326,C1327,C1328,C1335,C1336,C1337,C1338,C1353,C1354,C1355,C1356,C1371,C1372,C1373,C1374 |  |  |  |  |  |  |
|  |  |  |  |  | 19 | 620135Y00-012-G |  | CAP,2.2uF,+/-20%,X6S,10V,G,SMD0402 | WALSIN TECHNOLOGY CORPORATION | 0402S225M100CT |  | G |  |  |  |  |  |  |  |
| Multi | Y | 2 | Y(3) | 20 | 20 | 620102S00-015-G | - | CAP,33pF,+/-5%,NPO(C0G),50V,G,SMD0402 | MURATA ELEC. NORTH AMERICA | GRM1555C1H330J | 13 | G | PUAC3,PSAC3,PRAC3,PQAC3,PPAC3,PIAC3,PFAC3,PEAC3,C1420,C1421,C1653,C1654,C2146 |  |  |  |  |  |  |
|  |  |  |  |  | 20 | 620102S06-012-G |  | CAP,33pF,+/-5%,NPO(C0G),50V,G,SMD0402 | WALSIN TECHNOLOGY CORPORATION | 0402N330J500CT |  | G |  |  |  |  |  |  |  |
|  |  |  |  |  | 20 | 620102S00-023-G |  | CAP,33pF,+/-5%,NPO(C0G),50V,G,SMD0402 | TAIYO ELECTRIC IND.CO.LTD | UMK105CG330JV-F |  | G |  |  |  |  |  |  |  |
|  |  |  |  |  | 20 | 620102S00-026-G |  | CAP,33pF,+/-5%,NPO(C0G),50V,G,SMD0402 | SAMSUNG SEMICONDUCTOR | CL05C330JB5NNNC |  | G |  |  |  |  |  |  |  |
| Multi | ND | ND | Y(1) | 21 | 21 | 620109S00-023-G |  | CAP,4.7uF,+/-10%,X7R,10V,G,SMD0805 | TAIYO ELECTRIC IND.CO.LTD | LMK212B7475KG-T | 14 | G | C1424,C1427,C1451,C1455,C1459,C1464,C1466,C1468,C1470,C1499,C1533,C1577,C1585,C1596 |  |  |  |  |  |  |
|  |  |  |  |  | 21 | 620109S00-026-G |  | CAP,4.7uF,+/-10%,X7R,10V,G,SMD0805 | SAMSUNG SEMICONDUCTOR | CL21B475KPFNNNE |  | G |  |  |  |  |  |  |  |
|  |  |  |  |  | 21 | 620109S00-015-G |  | CAP,4.7uF,+/-10%,X7R,10V,G,SMD0805 | MURATA ELEC. NORTH AMERICA | GRM21BR71A475K |  | G |  |  |  |  |  |  |  |
| Multi | Y | 2 | Y(1) | 22 | 22 | 620109200-015-G |  | CAP,10uF,+/-10%,X7R,6.3V,G,SMD0805 | MURATA ELEC. NORTH AMERICA | GRM21BR70J106K | 7 | G | C1439,C1440,C1447,C1448,C1456,C1623,C1747 |  |  |  |  |  |  |
|  |  |  |  |  | 22 | 620109200-023-G |  | CAP,10uF,+/-10%,X7R,6.3V,G,SMD0805 | TAIYO ELECTRIC IND.CO.LTD | JMK212B7106KG-T |  | G |  |  |  |  |  |  |  |
|  |  |  |  |  | 22 | 620109200-026-G |  | CAP,10uF,+/-10%,X7R,6.3V,G,SMD0805 | SAMSUNG SEMICONDUCTOR | CL21B106KQQNNNE |  | G |  |  |  |  |  |  |  |
| Multi | ND |  | Y(1) | 23 | 23 | 620115801-015-G |  | CAP,22uF,+/-10%,X7R,10V,G,SMD1206 | MURATA ELEC. NORTH AMERICA | GRM31CR71A226KE15L | 17 | G | C1458,C1463,C1486,C1489,C1492,C1774,C1775,C1793,C1795,C1839,C1840,C1883,C1885,C1938,C1939,C1950,C1976 |  |  |  |  |  |  |
|  |  |  |  |  | 23 | 620115800-023-G |  | CAP,22uF,+/-10%,X7R,10V,G,SMD1206 | TAIYO ELECTRIC IND.CO.LTD | LMK316B7226KL-TR |  | G |  |  |  |  |  |  |  |
|  |  |  |  |  | 23 | 620115800-026-G |  | CAP,22uF,+/-10%,X7R,10V,G,SMD1206 | SAMSUNG SEMICONDUCTOR | CL31B226KPHNNNE |  | G |  |  |  |  |  |  |  |
| Multi | Y | 2 | ND | 24 | 24 | 620108000-015-G | - | CAP,100pF,+/-5%,NPO(C0G),50V,G,SMD0402 | MURATA ELEC. NORTH AMERICA | GRM1555C1H101J | 28 | G | PSPC4,PIPC4,PFPC4,PEPC4,PBAC4,PAAC4,PSRC9,PBNC12,PANC12,PSLC14,PSFC14,PSEC14,PSDC14,PEEC14,PEDC14,PBNC14,PANC14,PSIC20,PETC20,PERC20,C1473,C1474,C1554,C1559,C1565,C1567,C2041,C2114 |  |  |  |  |  |  |
|  |  |  |  |  | 24 | 62010800A-012-G |  | CAP,100pF,+/-5%,NPO(C0G),50V,G,SMD0402 | WALSIN TECHNOLOGY CORPORATION | 0402N101J500CT |  | G |  |  |  |  |  |  |  |
|  |  |  |  |  | 24 | 620108000-026-G |  | CAP,100pF,+/-5%,NPO(C0G),50V,G,SMD0402 | SAMSUNG SEMICONDUCTOR | CL05C101JB5NNNC |  | G |  |  |  |  |  |  |  |
|  |  |  |  |  | 24 | 620108000-023-G |  | CAP,100pF,+/-5%,NPO(C0G),50V,G,SMD0402 | TAIYO ELECTRIC IND.CO.LTD | UMK105CG101JV-F |  | G |  |  |  |  |  |  |  |
| Multi | ND | ND | Y(3) | 25 | 25 | 62010MU00-015-G | - | CAP,20pF,+/-5%,NPO(C0G),50V,G,SMD0402 | MURATA ELEC. NORTH AMERICA | GRM1555C1H200J | 2 | G | C1476,C1477 |  |  |  |  |  |  |
|  |  |  |  |  | 25 | 62012UJ00-012-G |  | CAP,20pF,+/-5%,NPO(C0G),50V,G,SMD0402 | WALSIN TECHNOLOGY CORPORATION | 0402N200J500CT |  | G |  |  |  |  |  |  |  |
|  |  |  |  |  | 25 | 62010MU00-026-G |  | CAP,20pF,+/-5%,NPO(C0G),50V,G,SMD0402 | SAMSUNG SEMICONDUCTOR | CL05C200JB5NNNC |  | G |  |  |  |  |  |  |  |
| Multi | Y |  | Y(1) | 26 | 26 | 62010DW00-015-G |  | CAP,10uF,+/-10%,X7R,16V,G,SMD1206 | MURATA ELEC. NORTH AMERICA | GRM31CR71C106K | 11 | G | C1478,C1479,C1485,C1495,C1584,C1778,C1786,C1832,C1875,C1942,C2035 |  |  |  |  |  |  |
|  |  |  |  |  | 26 | 62010DW00-026-G |  | CAP,10uF,+/-10%,X7R,16V,G,SMD1206 | SAMSUNG SEMICONDUCTOR | CL31B106KOHNNNE |  | G |  |  |  |  |  |  |  |
|  |  |  |  |  | 26 | 62010DW00-023-G |  | CAP,10uF,+/-10%,X7R,16V,G,SMD1206 | TAIYO ELECTRIC IND.CO.LTD | EMK316B7106KL-TD |  | G |  |  |  |  |  |  |  |
| Multi | ND |  | Y(3) | 27 | 27 | 62010MF00-015-G |  | CAP,100pF,+/-10%,X7R,16V,G,SMD0201 | MURATA ELEC. NORTH AMERICA | GRM033R71C101K | 6 | G | C1502,C1592,C1598,C1601,C1604,C1607 |  |  |  |  |  |  |
|  |  |  |  |  | 27 | 62010MF00-012-G |  | CAP,100pF,+/-10%,X7R,16V,G,SMD0201 | WALSIN TECHNOLOGY CORPORATION | 0201B101K160CT |  | G |  |  |  |  |  |  |  |
| Multi | ND | ND | Y(3) | 28 | 28 | 62010QB00-015-G | - | CAP,10nF,+/-10%,X7R,50V,G,SMD0402 | MURATA ELEC. NORTH AMERICA | GRM155R71H103K | 13 | G | PSIC7,C1541,C1679,C1680,C1681,C1682,C1684,C1685,C1686,C1688,C1704,C1710,C2069 |  |  |  |  |  |  |
|  |  |  |  |  | 28 | 62010QB00-012-G |  | CAP,10nF,+/-10%,X7R,50V,G,SMD0402 | WALSIN TECHNOLOGY CORPORATION | 0402B103K500CT |  | G |  |  |  |  |  |  |  |
|  |  |  |  |  | 28 | 62010QB00-026-G |  | CAP,10nF,+/-10%,X7R,50V,G,SMD0402 | SAMSUNG SEMICONDUCTOR | CL05B103KB5NNNC |  | G |  |  |  |  |  |  |  |
|  |  |  |  |  | 28 | 62010QB00-023-G |  | CAP,10nF,+/-10%,X7R,50V,G,SMD0402 | TAIYO ELECTRIC IND.CO.LTD | UMK105B7103KV-F |  | G |  |  |  |  |  |  |  |
| Multi | Y | 2 | Y(3) | 29 | 29 | 62010GW00-015-G | - | CAP,10pF,+/-5%,NPO,50V,G,SMD0402 | MURATA ELEC. NORTH AMERICA | GRM1555C1H100J | 5 | G | C1542,C1555,C1560,C1564,C1566 |  |  |  |  |  |  |
|  |  |  |  |  | 29 | 620102D05-012-G |  | CAP,10pF,+/-5%,NPO,50V,G,SMD0402 | WALSIN TECHNOLOGY CORPORATION | 0402N100J500CT |  | G |  |  |  |  |  |  |  |
|  |  |  |  |  | 29 | 620102D00-026-G |  | CAP,10pF,+/-5%,NPO(C0G),50V,G,SMD0402 | SAMSUNG SEMICONDUCTOR | CL05C100JB5NNNC |  | G |  |  |  |  |  |  |  |
| Multi | ND | ND | Y(3) | 30 | 30 | 62010K200-015-G | - | CAP,12pF,+/-5%,NPO(C0G),50V,G,SMD0402 | MURATA ELEC. NORTH AMERICA | GRM1555C1H120J | 8 | G | C1546,C1547,C1548,C1549,C1550,C1551,C1655,C1656 |  |  |  |  |  |  |
|  |  |  |  |  | 30 | 62010K207-012-G |  | CAP,12pF,+/-5%,NPO(C0G),50V,G,SMD0402 | WALSIN TECHNOLOGY CORPORATION | 0402N120J500CT |  | G |  |  |  |  |  |  |  |
|  |  |  |  |  | 30 | 62010K200-023-G |  | CAP,12pF,+/-5%,NPO(C0G),50V,G,SMD0402 | TAIYO ELECTRIC IND.CO.LTD | UMK105CG120JV-F |  | G |  |  |  |  |  |  |  |
|  |  |  |  |  | 30 | 62010K200-026-G |  | CAP,12pF,+/-5%,NPO(C0G),50V,G,SMD0402 | SAMSUNG SEMICONDUCTOR | CL05C120JB5NNNC |  | G |  |  |  |  |  |  |  |
| Multi | Y | 2 | Y(1) | 31 | 31 | 62011D900-015-G | - | CAP,22uF,+/-10%,X7R,6.3V,G,SMD1206 | MURATA ELEC. NORTH AMERICA | GRM31CR70J226K | 2 | G | C1563,C1746 |  |  |  |  |  |  |
|  |  |  |  |  | 31 | 62011D900-023-G |  | CAP,22uF,+/-10%,X7R,6.3V,G,SMD1206 | TAIYO ELECTRIC IND.CO.LTD | JMK316B7226KL-T |  | G |  |  |  |  |  |  |  |
|  |  |  |  |  | 31 | 62011D900-026-G |  | CAP,22uF,+/-10%,X7R,6.3V,G,SMD1206 | SAMSUNG SEMICONDUCTOR | CL31B226KQHNNNE |  | G |  |  |  |  |  |  |  |
| Multi | ND | ND | Y(3) | 32 | 32 | 620100L00-015-G | - | CAP,22pF,+/-5%,NPO(C0G),50V,G,SMD0402 | MURATA ELEC. NORTH AMERICA | GRM1555C1H220J | 12 | G | C1657,C1658,C1659,C1660,C1661,C1662,C1663,C1664,C1665,C1666,C1668,C1669 |  |  |  |  |  |  |
|  |  |  |  |  | 32 | 620100L08-012-G |  | CAP,22pF,+/-5%,NPO(C0G),50V,G,SMD0402 | WALSIN TECHNOLOGY CORPORATION | 0402N220J500CT |  | G |  |  |  |  |  |  |  |
|  |  |  |  |  | 32 | 620100L00-023-G |  | CAP,22pF,+/-5%,NPO(C0G),50V,G,SMD0402 | TAIYO ELECTRIC IND.CO.LTD | UMK105CG220JV-F |  | G |  |  |  |  |  |  |  |
|  |  |  |  |  | 32 | 620100L00-026-G |  | CAP,22pF,+/-5%,NPO(C0G),50V,G,SMD0402 | SAMSUNG SEMICONDUCTOR | CL05C220JB5NNNC |  | G |  |  |  |  |  |  |  |
| Multi | ND |  | N | 33 | 33 | 620109N00-015-G |  | CAP,2.2uF,+/-10%,X7R,10V,G,SMD0603 | MURATA ELEC. NORTH AMERICA | GRM188R71A225K | 8 | G | C1683,C1687,C1703,C1709,C1717,C1721,C1725,C1729 |  |  |  |  |  |  |
|  |  |  |  |  | 33 | 620109N00-023-G |  | CAP,2.2uF,+/-10%,X7R,10V,G,SMD0603 | TAIYO ELECTRIC IND.CO.LTD | LMK107B7225KA-T |  | G |  |  |  |  |  |  |  |
|  |  |  |  |  | 33 | 620109N00-026-G |  | CAP,2.2uF,+/-10%,X7R,10V,G,SMD0603 | SAMSUNG SEMICONDUCTOR | CL10B225KP8NNNC |  | G |  |  |  |  |  |  |  |
| Multi | ND | ND | Y(1) | 34 | 34 | 62012A400-015-G | - | CAP,100nF,+/-10%,X7R,25V,G,SMD0402 | MURATA ELEC. NORTH AMERICA | GRM155R71E104KE14D | 88 | G | PSTC1,PSLC1,PSFC1,PSEC1,PSDC1,PQPC1,PFRC1,PEEC1,PEDC1,PSUC3,PSTC6,PSLC6,PSFC6,PSEC6,PSDC6,PQPC6,PFRC6,PEEC6,PEDC6,PANC6,PBNC7,PBMC10,PBFC10,PBEC10,PBAC10,PAMC10,PAFC10,PAEC10,PAAC10,PSIC21,PETC21,PERC21,PBFC58,PBEC58,PAFC58,PAEC58,PBMC59,PAMC59,PBAC123,PAAC123,C1689,C1695,C1696,C1697,C1698,C1705,C1711,C1770,C1771,C1772,C1773,C1776,C1777,C1779,C1810,C1816,C1817,C1818,C1857,C1863,C1864,C1865,C1900,C1906,C1907,C1908,C1934,C1935,C1936,C1937,C1944,C1945,C1971,C1972,C1973,C2030,C2031,PSPC3002,PIPC3002,PFPC3002,PEPC3002,PSRC3006,PSPC3008,PIPC3008,PFPC3008,PEPC3008,PSRC3009,PSRC3011 |  |  |  |  |  |  |
|  |  |  |  |  | 34 | 62012A400-023-G |  | CAP,100nF,+/-10%,X7R,25V,G,SMD0402 | TAIYO ELECTRIC IND.CO.LTD | TMK105B7104KV-FR |  | G |  |  |  |  |  |  |  |
|  |  |  |  |  | 34 | 62012A400-026-G |  | CAP,100nF,+/-10%,X7R,25V,G,SMD0402 | SAMSUNG SEMICONDUCTOR | CL05B104KA5NNNC |  | G |  |  |  |  |  |  |  |
|  |  |  |  |  | 34 | 62012A400-012-G |  | CAP,100nF,+/-10%,X7R,25V,G,SMD0402 | WALSIN TECHNOLOGY CORPORATION | 0402B104K250CT |  | G |  |  |  |  |  |  |  |
| Multi | Y | 2 | Y(3) | 35 | 35 | 620103K00-015-G | - | CAP,1nF,+/-10%,X7R,50V,G,SMD0402 | MURATA ELEC. NORTH AMERICA | GRM155R71H102K | 16 | G | PHAC2,PUAC7,PSAC7,PRAC7,PQAC7,PPAC7,PIAC7,PFAC7,PEAC7,PBMC60,PAMC60,PBAC124,PAAC124,C1690,C1706,C1712 |  |  |  |  |  |  |
|  |  |  |  |  | 35 | 620103K00-012-G |  | CAP,1nF,+/-10%,X7R,50V,G,SMD0402 | WALSIN TECHNOLOGY CORPORATION | 0402B102K500CT |  | G |  |  |  |  |  |  |  |
|  |  |  |  |  | 35 | 620103K00-026-G |  | CAP,1nF,+/-10%,X7R,50V,G,SMD0402 | SAMSUNG SEMICONDUCTOR | CL05B102KB5NNNC |  | G |  |  |  |  |  |  |  |
|  |  |  |  |  | 35 | 620103K00-023-G |  | CAP,1nF,+/-10%,X7R,50V,G,SMD0402 | TAIYO ELECTRIC IND.CO.LTD | UMK105B7102KV-F |  | G |  |  |  |  |  |  |  |
| Multi | Y | 2 | Y(3) | 36 | 36 | 620107600-015-G | - | CAP,27pF,+/-5%,NPO(C0G),50V,G,SMD0402 | MURATA ELEC. NORTH AMERICA | GRM1555C1H270J | 2 | G | C1707,C1708 |  |  |  |  |  |  |
|  |  |  |  |  | 36 | 620107600-011-G |  | CAP,27pF,+/-5%,NPO(C0G),50V,G,SMD0402 | YAGEO CORPORATION COMPONENT | CC0402JRNPO9BN270 |  | G |  |  |  |  |  |  |  |
|  |  |  |  |  | 36 | 620107600-012-G |  | CAP,27pF,+/-5%,NPO(C0G),50V,G,SMD0402 | WALSIN TECHNOLOGY CORPORATION | 0402N270J500LT |  | G |  |  |  |  |  |  |  |
|  |  |  |  |  | 36 | 620107600-023-G |  | CAP,27pF,+/-5%,NPO(C0G),50V,G,SMD0402 | TAIYO ELECTRIC IND.CO.LTD | UMK105CG270JV-F |  | G |  |  |  |  |  |  |  |
|  |  |  |  |  | 36 | 620107600-025-G |  | CAP,27pF,+/-5%,NPO(C0G),50V,G,SMD0402 | KEMET ELECTRONICS CORPORATION | C0402C270J5GAC |  | G |  |  |  |  |  |  |  |
|  |  |  |  |  | 36 | 620107600-026-G |  | CAP,27pF,+/-5%,NPO(C0G),50V,G,SMD0402 | SAMSUNG SEMICONDUCTOR | CL05C270JB5NNNC |  | G |  |  |  |  |  |  |  |
|  |  |  |  |  | 36 | 620107602-012-G |  | CAP,27pF,+/-5%,NPO(C0G),50V,G,SMD0402 | WALSIN TECHNOLOGY CORPORATION | 0402N270J500CT |  | G |  |  |  |  |  |  |  |
| Multi | Y | 2 | Y(3) | 37 | 37 | 620112900-015-G | - | CAP,47nF,+/-10%,X7R,25V,G,SMD0402 | MURATA ELEC. NORTH AMERICA | GRM155R71E473K | 4 | G | C1734,C1735,C1736,C1739 |  |  |  |  |  |  |
|  |  |  |  |  | 37 | 620112900-012-G |  | CAP,47nF,+/-10%,X7R,25V,G,SMD0402 | WALSIN TECHNOLOGY CORPORATION | 0402B473K250CT |  | G |  |  |  |  |  |  |  |
| Multi | Y | 2 | Y(3) | 38 | 38 | 620103U00-015-G | - | CAP,470pF,+/-10%,X7R,50V,G,SMD0402 | MURATA ELEC. NORTH AMERICA | GRM155R71H471K | 14 | G | PBMC3,PBFC3,PBEC3,PBAC3,PAMC3,PAFC3,PAEC3,PAAC3,PALC42,PALC43,PBLC58,PBLC59,C1737,C1741 |  |  |  |  |  |  |
|  |  |  |  |  | 38 | 620103U00-012-G |  | CAP,470pF,+/-10%,X7R,50V,G,SMD0402 | WALSIN TECHNOLOGY CORPORATION | 0402B471K500CT |  | G |  |  |  |  |  |  |  |
|  |  |  |  |  | 38 | 620103U00-026-G |  | CAP,470pF,+/-10%,X7R,50V,G,SMD0402 | SAMSUNG SEMICONDUCTOR | CL05B471KB5NNNC |  | G |  |  |  |  |  |  |  |
|  |  |  |  |  | 38 | 620103U00-023-G |  | CAP,470pF,+/-10%,X7R,50V,G,SMD0402 | TAIYO ELECTRIC IND.CO.LTD | UMK105B7471KV-F |  | G |  |  |  |  |  |  |  |
| Multi | ND | ND | Y(1) | 39 | 39 | 62011HS01-015-G |  | CAP,10uF,+/-10%,X7R,25V,G,SMD1206 | MURATA ELEC. NORTH AMERICA | GRM31CR71E106K | 8 | G | C1769,C1804,C1850,C1894,C1933,C1958,C1970,C2032 |  |  |  |  |  |  |
|  |  |  |  |  | 39 | 62011HS00-026-G |  | CAP,10uF,+/-10%,X7R,25V,G,SMD1206 | SAMSUNG SEMICONDUCTOR | CL31B106KAHNNNE |  | G |  |  |  |  |  |  |  |
|  |  |  |  |  | 39 | 62011HS00-023-G |  | CAP,10uF,+/-10%,X7R,25V,G,SMD1206 | TAIYO ELECTRIC IND.CO.LTD | TMK316B7106KL-TD |  | G |  |  |  |  |  |  |  |
| Multi | Y | 2 | Y(3) | 40 | 40 | 62010G800-015-G | - | CAP,22nF,+/-10%,X7R,16V,G,SMD0402 | MURATA ELEC. NORTH AMERICA | GRM155R71C223K | 3 | G | PHAC4,C2063,C2129 |  |  |  |  |  |  |
|  |  |  |  |  | 40 | 62010G800-012-G |  | CAP,22nF,+/-10%,X7R,16V,G,SMD0402 | WALSIN TECHNOLOGY CORPORATION | 0402B223K160CT |  | G |  |  |  |  |  |  |  |
|  |  |  |  |  | 40 | 62010G800-026-G |  | CAP,22nF,+/-10%,X7R,16V,G,SMD0402 | SAMSUNG SEMICONDUCTOR | CL05B223KO5NNNC |  | G |  |  |  |  |  |  |  |
|  |  |  |  |  | 40 | 62010G800-023-G |  | CAP,22nF,+/-10%,X7R,16V,G,SMD0402 | TAIYO ELECTRIC IND.CO.LTD | EMK105B7223KV-F |  | G |  |  |  |  |  |  |  |
| Multi | ND | ND | Y(3) | 41 | 41 | 620110V00-015-G | - | CAP,1.2nF,+/-10%,X7R,50V,G,SMD0402 | MURATA ELEC. NORTH AMERICA | GRM155R71H122K | 1 | G | C2066 |  |  |  |  |  |  |
|  |  |  |  |  | 41 | 620110V00-026-G |  | CAP,1.2nF,+/-10%,X7R,50V,G,SMD0402 | SAMSUNG SEMICONDUCTOR | CL05B122KB5NNNC |  | G |  |  |  |  |  |  |  |
|  |  |  |  |  | 41 | 620110V00-023-G |  | CAP,1.2nF,+/-10%,X7R,50V,G,SMD0402 | TAIYO ELECTRIC IND.CO.LTD | UMK105B7122KV-F |  | G |  |  |  |  |  |  |  |
| Multi | ND | ND | Y(1) | 42 | 42 | 62012TW00-015-G | - | CAP,470nF,+/-10%,X7R,16V,G,SMD0402 | MURATA ELEC. NORTH AMERICA | GRM155R71C474KE01D | 2 | G | C2081,C2082 |  |  |  |  |  |  |
|  |  |  |  |  | 42 | 62012YQ00-026-G |  | CAP,470nF,+/-10%,X7R,10V,G,SMD0402 | SAMSUNG SEMICONDUCTOR | CL05B474KP5NNNC |  | G |  |  |  |  |  |  |  |
| Multi | ND |  | Y(1) | 43 | 43 | 62012PS00-015-G |  | CAP,10uF,+/-20%,X6S,4V,G,SMD0402 | MURATA ELEC. NORTH AMERICA | GRM155C80G106M | 495 | G | PBFC28,PBEC28,PAFC28,PAEC28,PBMC29,PBFC29,PBEC29,PBAC29,PAMC29,PAFC29,PAEC29,PAAC29,PBMC30,PBFC30,PBEC30,PBAC30,PAMC30,PAFC30,PAEC30,PAAC30,PBMC31,PBFC31,PBEC31,PBAC31,PAMC31,PAFC31,PAEC31,PAAC31,PBMC32,PBFC32,PBEC32,PBAC32,PAMC32,PAFC32,PAEC32,PAAC32,PBMC33,PBFC33,PBEC33,PBAC33,PAMC33,PAFC33,PAEC33,PAAC33,PBMC34,PBFC34,PBEC34,PBAC34,PAMC34,PAFC34,PAEC34,PAAC34,PBMC35,PBFC35,PBEC35,PBAC35,PAMC35,PAFC35,PAEC35,PAAC35,PBMC36,PBFC36,PBEC36,PBAC36,PAMC36,PAFC36,PAEC36,PAAC36,PBMC37,PBFC37,PBEC37,PBAC37,PAMC37,PAFC37,PAEC37,PAAC37,PBMC38,PBFC38,PBEC38,PBAC38,PAMC38,PAFC38,PAEC38,PAAC38,PBMC39,PBFC39,PBEC39,PBAC39,PAMC39,PAFC39,PAEC39,PAAC39,PBMC40,PBFC40,PBEC40,PBAC40,PAMC40,PAFC40,PAEC40,PAAC40,PBMC41,PBFC41,PBEC41,PBAC41,PAMC41,PAFC41,PAEC41,PAAC41,PBMC42,PBFC42,PBEC42,PBAC42,PAMC42,PAFC42,PAEC42,PAAC42,PBMC43,PBFC43,PBEC43,PBAC43,PAMC43,PAFC43,PAEC43,PAAC43,PBMC44,PBFC44,PBEC44,PBAC44,PAMC44,PAFC44,PAEC44,PAAC44,PBMC45,PBFC45,PBEC45,PBAC45,PAMC45,PAFC45,PAEC45,PAAC45,PBMC46,PBFC46,PBEC46,PBAC46,PAMC46,PAFC46,PAEC46,PAAC46,PBMC47,PBFC47,PBEC47,PBAC47,PAMC47,PAFC47,PAEC47,PAAC47,PBMC48,PBFC48,PBEC48,PBAC48,PAMC48,PAFC48,PAEC48,PAAC48,PBMC49,PBFC49,PBEC49,PBAC49,PAMC49,PAFC49,PAEC49,PAAC49,PBMC50,PBFC50,PBEC50,PBAC50,PAMC50,PAFC50,PAEC50,PAAC50,PBMC51,PBFC51,PBEC51,PBAC51,PAMC51,PAFC51,PAEC51,PAAC51,PBMC52,PBFC52,PBEC52,PBAC52,PAMC52,PAFC52,PAEC52,PAAC52,PBMC53,PBFC53,PBEC53,PBAC53,PAMC53,PAFC53,PAEC53,PAAC53,PBMC54,PBFC54,PBEC54,PBAC54,PAMC54,PAFC54,PAEC54,PAAC54,PBMC55,PBFC55,PBEC55,PBAC55,PAMC55,PAFC55,PAEC55,PAAC55,PBMC56,PBFC56,PBEC56,PBAC56,PAMC56,PAFC56,PAEC56,PAAC56,PBMC57,PBFC57,PBEC57,PBAC57,PAMC57,PAFC57,PAEC57,PAAC57,PBMC58,PBAC58,PAMC58,PAAC58,PBAC59,PAAC59,PBAC60,PAAC60,PBAC61,PAAC61,PBFC62,PBEC62,PBAC62,PAFC62,PAEC62,PAAC62,PBMC63,PBFC63,PBEC63,PBAC63,PAMC63,PAFC63,PAEC63,PAAC63,PBMC64,PBFC64,PBEC64,PBAC64,PAMC64,PAFC64,PAEC64,PAAC64,PBMC65,PBFC65,PBEC65,PBAC65,PAMC65,PAFC65,PAEC65,PAAC65,PBMC66,PBFC66,PBEC66,PBAC66,PAMC66,PAFC66,PAEC66,PAAC66,PBMC67,PBFC67,PBEC67,PBAC67,PAMC67,PAFC67,PAEC67,PAAC67,PBMC68,PBFC68,PBEC68,PBAC68,PAMC68,PAFC68,PAEC68,PAAC68,PBMC69,PBFC69,PBEC69,PBAC69,PAMC69,PAFC69,PAEC69,PAAC69,PBMC70,PBFC70,PBEC70,PBAC70,PAMC70,PAFC70,PAEC70,PAAC70,PBMC71,PBFC71,PBEC71,PBAC71,PAMC71,PAFC71,PAEC71,PAAC71,PBMC72,PBAC72,PAMC72,PAAC72,PBAC73,PAAC73,PBAC74,PAAC74,PBAC75,PAAC75,PBAC76,PAAC76,PBAC77,PAAC77,PBAC78,PAAC78,PBAC81,PAAC81,PBAC82,PAAC82,PBAC83,PAAC83,PBAC84,PAAC84,PBAC85,PAAC85,PBAC86,PAAC86,PBAC87,PAAC87,PBAC88,PAAC88,PBAC89,PAAC89,PBAC90,PAAC90,PBAC91,PAAC91,PBAC92,PAAC92,PBAC93,PAAC93,PBAC94,PAAC94,PBAC95,PAAC95,PBAC96,PAAC96,PBAC97,PAAC97,PBAC98,PAAC98,PBAC99,PAAC99,PBAC100,PAAC100,PBAC101,PAAC101,PBAC102,PAAC102,PBAC103,PAAC103,PBAC104,PAAC104,PBAC105,PAAC105,PBAC106,PAAC106,PBAC107,PAAC107,PBAC108,PAAC108,PBAC109,PAAC109,PBAC110,PAAC110,PBAC113,PAAC113,PBAC114,PAAC114,PBAC115,PAAC115,PBAC116,PAAC116,PBAC117,PAAC117,PBAC118,PAAC118,PBAC119,PAAC119,PBAC120,PAAC120,PBAC121,PAAC121,PBAC122,PAAC122,PBAC127,PAAC127,PBAC128,PAAC128,PBAC129,PAAC129,PBAC130,PAAC130,PBAC131,PAAC131,PBAC132,PAAC132,PBAC133,PAAC133,PBAC134,PAAC134,PBAC135,PAAC135,PBAC136,PAAC136,PBAC137,PAAC137,PBAC138,PAAC138,PBAC139,PAAC139,PBAC140,PAAC140,PBAC141,PAAC141,PBAC142,PAAC142,PBAC143,PAAC143,PBAC144,PAAC144,PBAC145,PAAC145,PBAC146,PAAC146,PBAC147,PAAC147,PBAC148,PAAC148,PBAC149,PAAC149,PBAC150,PAAC150,PBAC151,PAAC151,PBAC152,PAAC152,PBAC153,PAAC153,PBAC154,PAAC154,PBAC155,PAAC155,PBAC156,PAAC156,PBFC501,PBEC501,PAFC501,PAEC501,C2168,C2169,C2170,C2172,C2173,C2174,C2175,C2176,C2177,C2178,C2179 |  |  |  |  |  |  |
|  |  |  |  |  | 43 | 62012PS00-023-G |  | CAP,10uF,+/-20%,X6S,4V,G,SMD0402 | TAIYO ELECTRIC IND.CO.LTD | AMK105CC6106MV-F |  | G |  |  |  |  |  |  |  |
| Multi | Y |  | Y(1) | 44 | 44 | 620130V00-015-G |  | CAP,10uF,+/-20%,X6S,16V,G,SMD0603 | MURATA ELEC. NORTH AMERICA | GRM188C81C106MA73D | 5 | G | PBNC1,PANC8,PQPC16,C2188,PSRC3008 |  |  |  |  |  |  |
|  |  |  |  |  | 44 | 620130V00-023-G |  | CAP,10uF,+/-20%,X6S,16V,G,SMD0603 | TAIYO ELECTRIC IND.CO.LTD | EMK107BC6106MA-T |  | G |  |  |  |  |  |  |  |
| Single |  |  | Y(4) | 45 | 45 | 520300500-223-G |  | DIODE,Schottky,BAT54SLT1G,30V,0.2A,G,SOT23-3,SMD | ON SEMICONDUCTOR CORP | BAT54SLT1G | 7 | G | D9,D10,D11,D12,D13,D16,D18 |  |  |  |  |  |  |
| Multi | ND | ND | Y(4) | 46 | 46 | 520305J00-223-G |  | DIODE,Schottky,MBR130LSFT1G,30V,1A,G,SOD123FL-2,SMD | ON SEMICONDUCTOR CORP | MBR130LSFT1G | 1 | G | D14 |  |  |  |  |  |  |
|  |  |  |  |  | 46 | 52030GG00-031-G |  | Diode,Schottky,PMEG3010ER,30V,1A,SOD-123,2P,G | NXP SEMICONDUCTORS | PMEG3010ER |  | G |  |  |  |  |  |  |  |
| Single | Y | 1 | Y(3) | 47 | 47 | 520306Y00-223-G | WN533 | DIODE,Schottky Rectifier,MBR0530T1G,30V,0.5A,G,SOD123-2,SMD | ON SEMICONDUCTOR CORP | MBR0530T1G | 2 | G | D15,D17 |  |  |  |  |  |  |
| Multi |  |  | N | 48 | 48 | 520300A00-237-G |  | DIODE,Schottky,SD103AW-7-F,40V,0.35A,G,SOD123-2,SMD | DIODES INEORPORATION | SD103AW-7-F | 1 | G | D19 |  |  |  |  |  |  |
|  |  |  |  |  | 48 | 520302L00-223-G |  | Diode,Schottky,MBR0540T1G,40V,500mA,SOD-123,2P,G | ON SEMICONDUCTOR CORP | MBR0540T1G |  | G |  |  |  |  |  |  |  |
| Multi | ND | ND | N | 49 | 49 | 520100200-237-G |  | DIODE,Switching,1N4148W-7-F,100V,0.15A,G,SOD123-2,SMD | DIODES INEORPORATION | 1N4148W-7-F | 3 | G | PHAD6,D20,D21 |  |  |  |  |  |  |
|  |  |  |  |  | 49 | 520102P00-031-G |  | DIODE,Switching,BAS16H,100V,0.5A,G,SOD123F-2,SMD | NXP SEMICONDUCTORS | BAS16H |  | G |  |  |  |  |  |  |  |
| Multi | ND |  | N | 50 | 50 | 520308A00-237-G |  | Diode,Schottky,B0530WS-7-F,30V,500mA,G,SOD-323-2,SMD | DIODES INCORPORATION | B0530WS-7-F | 6 | G | D22,D23,D24,D25,D26,D27 |  |  |  |  |  |  |
|  |  |  |  |  | 50 | 520309600-031-G |  | Diode,Schottky,PMEG3005AEA,30V,500mA,SOD-323,2P,G | NXP SEMICONDUCTORS | PMEG3005AEA |  | G |  |  |  |  |  |  |  |
| Multi | ND |  | N | 51 | 51 | 52010MP00-237-G |  | Diode,Rectifier,ES2D-13-F,200V,2A,G,SMB-2,SMD | DIODES INCORPORATION | ES2D-13-F | 3 | G | D28,D35,D36 |  |  |  |  |  |  |
|  |  |  |  |  | 51 | 52010N000-223-G |  | Diode,Rectifier&Switching,MURS220T3G,200V,2A,SMB/DO-214AA,2P,G | ON SEMICONDUCTOR CORP | MURS220T3G |  | G |  |  |  |  |  |  |  |
| Multi | ND |  | N | 52 | 52 | 520308D00-237-G |  | DIODE,Schottky Rectifier,1N5819HW-7-F,40V,1A,G,SOD123-2,SMD | DIODES INCORPORATION | 1N5819HW-7-F | 1 | G | D33 |  |  |  |  |  |  |
|  |  |  |  |  | 52 | 52030P100-223-G |  | Diode,Schottky,MBR140SFT1G,40V,1A,SOD-123FL,2P,G | ON SEMICONDUCTOR CORP | MBR140SFT1G |  | G |  |  |  |  |  |  |  |
|  |  |  |  |  | 52 | 520318S00-223-G |  | Diode,Schottky,MBR140SFT3G,40V,1A,G,SOD-123FL-2,SMD | ON SEMICONDUCTOR CORP | MBR140SFT3G |  | G |  |  |  |  |  |  |  |
| Multi | ND | ND | N | 53 | 53 | 520401Y00-237-G | - | DIODE,Zener,BZT52C3V6-7-F,3.6V,5mA,G,SOD123-2,SMD | DIODES INEORPORATION | BZT52C3V6-7-F | 1 | G | D34 |  |  |  |  |  |  |
|  |  |  |  |  | 53 | 520407600-223-G |  | Diode,ZENER,MMSZ3V6T1G,3.6V,5mA,SOD-123,2P,G | ON SEMICONDUCTOR CORP | MMSZ3V6T1G |  | G |  |  |  |  |  |  |  |
| Multi | Y | 1 | N | 54 | 54 | 520304B00-237-G |  | DIODE,Schottky,BAT54WS-7-F,30V,0.1A,G,SOD323-2,SMD | DIODES INEORPORATION | BAT54WS-7-F | 3 | G | D53,D54,D56 |  |  |  |  |  |  |
|  |  |  |  |  | 54 | 520303500-223-G |  | Diode,Schottky,BAT54HT1G,30V,200mA,SOD-323,2P,G | ON SEMICONDUCTOR CORP | BAT54HT1G |  | G |  |  |  |  |  |  |  |
|  |  |  |  |  | 54 | 520308200-031-G |  | DIODE,Schottky,1PS76SB10,30V,200mA,G,SOD323-2,SMD | NXP SEMICONDUCTORS | 1PS76SB10 |  | G |  |  |  |  |  |  |  |
| Multi | ND | ND | N | 55 | 55 | 52030NP00-185-G |  | DIODE,Schottky,RB521S30,30V,200mA,G,SOD523-2,SMD | FAIRCHILD SEMICONDUCTOR CORP | RB521S30 | 1 | G | D57 |  |  |  |  |  |  |
|  |  |  |  |  | 55 | 52030NP00-031-G |  | Diode,Schottky,RB521S30,30V,200mA,SOD-523,2P,G | NXP SEMICONDUCTORS | RB521S30 |  | G |  |  |  |  |  |  |  |
|  |  |  |  |  | 55 | 52030AG00-237-G |  | DIODE,Schottky,SDM20U30-7,30V,0.2A,G,SOD523-2,SMD | DIODES INCORPORATION | SDM20U30-7 |  | G |  |  |  |  |  |  |  |
| Single | Y |  | N | 56 | 56 | 52180BC00-223-G |  | DIODE,Array-TVS,ESD8004MUTAG,G,UDFN-10,SMD | ON SEMICONDUCTOR CORP | ESD8004MUTAG | 1 | G | ED1 |  |  |  |  |  |  |
| Multi | ND |  | N | 57 | 57 | 521800900-227-G |  | DIODE,Array-TVS,SRV05-4.TCT,5V,12A,G,SOT23-6,SMD | SEMTECH CORPORATION. | SRV05-4.TCT | 2 | G | ED2,ED3 |  |  |  |  |  |  |
|  |  |  |  |  | 57 | 52180C200-086-G |  | Diode,Array-TVS,SRV05-4HTG,SOT-23,6P,G | LITTELFUSE FAR EAST PTE LTD | SRV05-4HTG |  | G |  |  |  |  |  |  |  |
| Multi | N | ND | Y(2) | 58 | 58 | 720101900-015-G | - | FB,60 Ohm@100MHz,+/-25%,3A,25mOhm,G,SMD0805 | MURATA ELEC. NORTH AMERICA | BLM21PG600SN1D | 1 | G | FB1 |  |  |  |  |  |  |
|  |  |  |  |  | 58 | 720101900-026-G |  | FB,60 Ohm@100MHz,+/-25%,3A,25mOhm,G,SMD0805 | SAMSUNG SEMICONDUCTOR | CIC21P600NE |  | G |  |  |  |  |  |  |  |
| Multi | N | ND | Y(1) | 59 | 59 | 720406E00-015-G | - | Common Choke,90Ohm@100MHz,+/-25%,220mA,G,SMD0805 | MURATA ELEC. NORTH AMERICA | DLW21HN900HQ2L | 3 | G | FL1,FL4,FL10 |  |  |  |  |  |  |
|  |  |  |  |  | 59 | 720405D00-016-G |  | Common Choke,90 Ohm@100MHz,Type,200mA,G,SMD0805 | TDK ELECTRONICS EUROPE GMBH | ACM2012E-900-2P-T01 |  | G |  |  |  |  |  |  |  |
|  |  |  |  |  | 59 | 720402300-129-G |  | Filter,Inductor type,Common Mode(CMODE),90Ohm@100MHz,Type,300mA,,SMD0805,G | MAG.LAYERS, SCIENTIFIC-TECHNICS (KUNSHAN) CO., LTD. | MCI-2012H-900 |  | G |  |  |  |  |  |  |  |
| Multi | ND | ND | Y(1) | 60 | 60 | 720400201-015-G | - | Filter,Common Mode,90Ohm@100MHz,+/-25%,330mA,G,SMD0805 | MURATA ELEC. NORTH AMERICA | DLW21HN900SQ2L | 7 | G | FL2,FL3,FL5,FL6,FL7,FL8,FL9 |  |  |  |  |  |  |
|  |  |  |  |  | 60 | 720400M00-059-G |  | Common Choke,90 Ohm@100MHz,+/-25%,400mA,G,SMD0805 | TAI-TECH ADVANCED ELECTRONICS CO., LTD. | WCM2012F2SF-900T04 |  | G |  |  |  |  |  |  |  |
|  |  |  |  |  | 60 | 720400800-016-G |  | Common Choke,90 Ohm@100MHz,+/-25%,400mA,190mOhm,2L,G,SMD0805 | TDK ELECTRONICS EUROPE GMBH | ACM2012-900-2P-T |  | G |  |  |  |  |  |  |  |
|  |  |  |  |  | 60 | 720400200-129-G |  | Common Choke,90 Ohm@100MHz,+/-25%,400mA,190mOhm,2L,G,SMD0805 | MAG.LAYERS, SCIENTIFIC-TECHNICS (KUNSHAN) CO., LTD. | MCI-2012-900 |  | G |  |  |  |  |  |  |  |
| Single | N | other | Y(3) | 61 | 61 | 730200800-101-G |  | Polyswitch,PTC,6V,1.5A,G,SMD1206 | BOURNS INC | MF-NSMF150-2 | 1 | G | FS1 |  |  |  |  |  |  |
| Single | ND |  | Y(1) | 62 | 62 | 730100400-086-G |  | Fuse,Very fast acting,3A,32V,G,SMD0603 | LITTELFUSE FAR EAST PTE LTD | 0467003.NR | 2 | G | FS2,FS3 |  |  |  |  |  |  |
| Multi | ND |  | Y(1) | 63 | 63 | 730102701-086-G |  | Fuse,Fast acting,32V,7A,G,SMD1206 | LITTELFUSE FAR EAST PTE LTD | 0440007.WR | 6 | G | FS4,FS9,FS12,FS15,FS16,FS21 |  |  |  |  |  |  |
|  |  |  |  |  | 63 | 730102704-088-G |  | Fuse,Fast acting,32V,7A,SMD1206,G | COOPER BUSSMANN, INC. | CC12H7A-TR |  | G |  |  |  |  |  |  |  |
| Multi | ND |  | Y(1) | 64 | 64 | 0438005.WRGT |  | Fuse,Fast acting,32V,5A,G,SMD0603 | LITTELFUSE FAR EAST PTE LTD | 0438005.WRGT | 7 | G | FS5,FS8,FS11,FS14,FS17,FS19,FS20 |  |  |  |  |  |  |
|  |  |  |  |  | 64 | 730103M00-086-G |  | Fuse,Fast acting,32V,5A,G,SMD0603 | LITTELFUSE FAR EAST PTE LTD | 0438005.WR |  | G |  |  |  |  |  |  |  |
|  |  |  |  |  | 64 | 730103M00-088-G |  | Fuse,Fast acting,32V,5A,SMD0603,G | COOPER BUSSMANN, INC. | CC06H5A-TR |  | G |  |  |  |  |  |  |  |
| Multi | ND | ND | Y(1) | 65 | 65 | 730102B01-086-G |  | Fuse,Fast acting,32V,1A,G,SMD0603 | LITTELFUSE FAR EAST PTE LTD | 0438001.WR | 5 | G | FS6,FS7,FS10,FS13,FS18 |  |  |  |  |  |  |
|  |  |  |  |  | 65 | 730102B03-088-G |  | Fuse,Fast acting,32V,1A,SMD0603,G | COOPER BUSSMANN, INC. | CC06H1A-TR |  | G |  |  |  |  |  |  |  |
| Single | N |  | Y(1) | 66 | 66 | 730102000-086-G |  | Fuse,Fast acting,24V,10A,G,SMD1206 | LITTELFUSE FAR EAST PTE LTD | 0501010.WR | 1 | G | FS22 |  |  |  |  |  |  |
| Single | ND |  | Y(1) | 67 | 67 | 730108F00-086-G |  | Fuse,Fast acting,500V,30A,G,SMD | LITTELFUSE FAR EAST PTE LTD | 0505030.MXP | 2 | G | FS27,FS28 |  |  |  |  |  |  |
| Single | N |  | Y(2) | 68 | 68 | 730106S00-088-G |  | Fuse,Fast acting,125V,15A,G,SMD2010 | COOPER BUSSMANN, INC. | CB61F15A-TR2 | 1 | G | FS29 |  |  |  |  |  |  |
| Multi | ND |  | N | 69 | 69 | 87898-0318 |  | CONN,Header,Pin Header,1X3,V/T,2.54mm,30u,G,SMD-3 | MOLEX INCORPORATED | 87898-0318 | 10 | G | J_BMC_DEBUG1,J1,J4,J5,J36,J41,J43,J48,J147,J149 |  |  |  |  |  |  |
|  |  |  |  |  | 69 | 34068LN00-317-G |  | CONN,Header,Pin Header,1X3,V/T,2.54mm,30u,G,SMD-3 | MOLEX INCORPORATED | 87898-0315 |  | G |  |  |  |  |  |  |  |
|  |  |  |  |  | 69 | 34068HT00-245-G |  | CONN,Header,Pin Header,1X3,V/T,Bla,2.54mm,30u,SMD-3 | AMPHENOL SHANGHAI CORP. | G800MU305010EU |  | G |  |  |  |  |  |  |  |
|  |  |  |  |  | 69 | 34068GU00-309-G |  | CONN,Header,Pin Header,1X3,V/T,Bla,2.54mm,30u,SMD-3 | SAMTEC INC. | TSM-103-01-S-SV-P-TR |  | G |  |  |  |  |  |  |  |
| Multi | N |  | N | 70 | 70 | 87898-0458 |  | CONN,Pin Header,1X4,V/T,Bla,2.54mm,30u,G,SMD-4 | MOLEX INCORPORATED | 87898-0458 | 1 | G | J148 |  |  |  |  |  |  |
|  |  |  |  |  | 70 | 340672300-317-G |  | CONN,Pin Header,1X4,V/T,Bla,2.54mm,30u,G,SMD-4 | MOLEX INCORPORATED | 87898-0455 |  | G |  |  |  |  |  |  |  |
|  |  |  |  |  | 70 | 34068VT00-GRT-G |  | CONN,Header,Pin Header,1X4,V/T,Bla,2.54mm,30u,G,SMD-4 | PINREX TECHNOLOGY CORP. | 212-91-04SBEJ |  | G |  |  |  |  |  |  |  |
|  |  |  |  |  | 70 | 340692T00-245-G |  | CONN,Header,Pin Header,1X4,V/T,Bla,2.54mm,30u,G,SMD-4 | AMPHENOL SHANGHAI CORP. | G800MR304010HR |  | G |  |  |  |  |  |  |  |
| Multi | N |  | N | 71 | 71 | 52112H800-289-G |  | LED,Blu,LTST-C193TBKT-LO,5V,20mA,G,SMD | LITE-ON TECHNOLOGY CORPORATION | LTST-C193TBKT-LO | 1 | G | LED1 |  |  |  |  |  |  |
|  |  |  |  |  | 71 | 52112H900-354-G |  | LED LAMP,LG-192DBK-CT/T-SD,Blue,24mcd@IF=5mA,475nm,999.9999V,20mA,N/A,,SMD0603,2P,G | Ligitek Electronics Co., Ltd. | LG-192DBK-CT/T-SD |  | G |  |  |  |  |  |  |  |
| Multi | N | 1 | N | 72 | 72 | 52111AE00-289-G |  | LED,Ora,LTST-C281KFKT-5A,5V,30mA,G,SMD0402 | LITE-ON TECHNOLOGY CORPORATION | LTST-C281KFKT-5A | 2 | G | LED2,LED6 |  |  |  |  |  |  |
|  |  |  |  |  | 72 | 52113GM00-290-G |  | LED LAMP,B1851UD--05D-000214,Orange,28.5mcd@IF=20mA,605nm,5V,20mA,N/A,,SMD0402,2P,G | HARVATEK CORPORATION | B1851UD--05D-000214 |  | G |  |  |  |  |  |  |  |
| Multi | N | 1 | N | 73 | 73 | 52111J100-289-G |  | LED,Gre,LTST-C281KGKT-5A,2.3V,30mA,G,SMD0402 | LITE-ON TECHNOLOGY CORPORATION | LTST-C281KGKT-5A | 2 | G | LED3,LED7 |  |  |  |  |  |  |
|  |  |  |  |  | 73 | 52113AE00-290-G |  | LED LAMP,B1851UYG-05D-000114,Ultra Bright Yellow Green,11.25mcd@IF=5mA,571nm,5V,20mA,N/A,,SMD0402,2P,G | HARVATEK CORPORATION | B1851UYG-05D-000114 |  | G |  |  |  |  |  |  |  |
| Single | ND |  | N | 74 | 74 | 52113AY00-289-G |  | LED,Red,LTL-42NEW8DH184P,5V,20mA,G,DIP-2 | LITE-ON TECHNOLOGY CORPORATION | LTL-42NEW8DH184P | 2 | G | LED8,LED9 |  |  |  |  |  |  |
| Single | ND |  | N | 75 | 75 | 52113B000-289-G |  | LED,Yellow,LTL-42NSV8DH184P,5V,20mA,G,DIP-2 | LITE-ON TECHNOLOGY CORPORATION | LTL-42NSV8DH184P | 2 | G | LED10,LED14 |  |  |  |  |  |  |
| Single | ND |  | N | 76 | 76 | 52113AW00-289-G |  | LED,Green,LTL-42NGY8DH184P,5V,20mA,G,DIP-2 | LITE-ON TECHNOLOGY CORPORATION | LTL-42NGY8DH184P | 2 | G | LED11,LED12 |  |  |  |  |  |  |
| Single | ND |  | N | 77 | 77 | 52113B100-289-G |  | LED,Blue,LTL42TB6NH184P,5V,30mA,G,DIP-2 | LITE-ON TECHNOLOGY CORPORATION | LTL42TB6NH184P | 1 | G | LED13 |  |  |  |  |  |  |
| Single | N |  | N | 78 | 78 | 52110FE00-289-G |  | LED,Red,LTST-C190KRKT,2.4V,30mA,G,SMD0603 | LITE-ON TECHNOLOGY CORPORATION | LTST-C190KRKT | 3 | G | LED63,LED64,LED65 |  |  |  |  |  |  |
| Multi | N | 1 | N | 79 | 79 | 52110LN00-289-G |  | LED,Gre,LTST-C191KGKT,2.4V,30mA,G,SMD0603 | LITE-ON TECHNOLOGY CORPORATION | LTST-C191KGKT | 37 | G | LED66,LED67,LED68,LED69,LED70,LED71,LED72,LED73,LED74,LED75,LED76,LED77,LED78,LED79,LED80,LED81,LED82,LED83,LED84,LED85,LED86,LED87,LED88,LED89,LED90,LED91,LED92,LED93,LED94,LED95,LED96,LED97,LED98,LED99,LED100,LED101,LED102 |  |  |  |  |  |  |
|  |  |  |  |  | 79 | 52110K100-030-G |  | LED LAMP,SML-512MWT86,Green,40mcd@If=20mA,N/A,5V,25mA,N/A,,SMD0603,2P,G | ROHM CORPORATION | SML-512MWT86 |  | G |  |  |  |  |  |  |  |
| Single | ND | ND | Y(1) | 80 | 80 | 21040HY00-283-G | - | IC,BROADCOM,BCM5719A1KFBG,A1,G,FBGA-256,SMD | BROADCOM SINGAPORE PTE LTD. | BCM5719A1KFBG | 1 | G | LOM1 |  |  |  |  |  |  |
| Multi | Y | Other | Y(2) | 81 | 81 | 720108301-015-G | - | FB,600 Ohm@100MHz,+/-25%,500mA,350mOhm,G,SMD0603 | MURATA ELEC. NORTH AMERICA | BLM18EG601SN1D | 14 | G | L2,L3,L4,L5,L6,L8,L9,L10,L11,L12,L13,L14,L15,L16 |  |  |  |  |  |  |
|  |  |  |  |  | 81 | 720105E00-059-G |  | FB,600 Ohm@100MHz,+/-25%,500mA,400mOhm,G,SMD0603 | TAI-TECH ADVANCED ELECTRONICS CO., LTD. | FCM1608KF-601T05 |  | G |  |  |  |  |  |  |  |
|  |  |  |  |  | 81 | 720105E00-016-G |  | FB,600 Ohm@100MHz,+/-25%,500mA,400mOhm,G,SMD0603 | TDK ELECTRONICS EUROPE GMBH | MMZ1608S601AT |  | G |  |  |  |  |  |  |  |
| Multi | ND | ND | N | 82 | 82 | 630332000-053-G |  | IND,3.3uH@100KHz,+/-20%,2.57A,26mOhm,SHLD,G,SMD | TOKO INC. | #A916CY-3R3M=P3 | 1 | G | L7 |  |  |  |  |  |  |
|  |  |  |  |  | 82 | 63035BF00-129-G |  | IND,3.3uH@100KHz,+/-20%,2.57A,26mOhm,SHLD,G,SMD | MAG.LAYERS, SCIENTIFIC-TECHNICS (KUNSHAN) CO., LTD. | MSCDRI-6035LC-3R3M-EH |  | G |  |  |  |  |  |  |  |
| Multi | Y | Other | Y(2) | 83 | 83 | 720106E00-015-G | - | FB,330 Ohm@100MHz,+/-25%,500mA,300mOhm,G,SMD0603 | MURATA ELEC. NORTH AMERICA | BLM18EG331TN1D | 1 | G | L17 |  |  |  |  |  |  |
|  |  |  |  |  | 83 | 72010YW01-129-G |  | FB,Multilayer,100mOhm,330Ohm@100MHz,+/-25%,2A,,SMD0603,G | MAG.LAYERS, SCIENTIFIC-TECHNICS (KUNSHAN) CO., LTD. | GMLB-160808-0330P-N8 |  | G |  |  |  |  |  |  |  |
| Single | ND | ND | N | 84 | 84 | 630100U00-016-G | - | IND,68nH@50MHz,+/-20%,50mA,300mOhm,G,SMD0603 | TDK ELECTRONICS EUROPE GMBH | MLF1608D68NMT | 3 | G | L18,L19,L20 |  |  |  |  |  |  |
| Single | ND | ND | Y(2) | 85 | 85 | 720107U00-015-G | - | FB,220 Ohm@100MHz,+/-25%,2A,50mOhm,G,SMD0805 | MURATA ELEC. NORTH AMERICA | BLM21PG221SN1D | 1 | G | L21 |  |  |  |  |  |  |
| Multi | ND | ND | N | 86 | 86 | 720105P00-016-G | - | FB,80 Ohm@100MHz,+/-25%,500mA,150mOhm,G,SMD0603 | TDK ELECTRONICS EUROPE GMBH | MMZ1608S800AT | 4 | G | L22,L23,L24,L25 |  |  |  |  |  |  |
|  |  |  |  |  | 86 | 72010WQ00-129-G |  | FB,Multilayer,40mOhm,80Ohm@100MHz,+/-25%,3A,,SMD0603,G | MAG.LAYERS, SCIENTIFIC-TECHNICS (KUNSHAN) CO., LTD. | GMLB-160808-0080P-N8 |  | G |  |  |  |  |  |  |  |
| Multi | ND | ND | Y(2) | 87 | 87 | 72010CB00-015-G | - | FB,22 Ohm@100MHz,+/-25%,6A,10mOhm,G,SMD0805 | MURATA ELEC. NORTH AMERICA | BLM21PG220SN1D | 3 | G | L26,L28,L47 |  |  |  |  |  |  |
|  |  |  |  |  | 87 | 72010CB00-059-G |  | FB,22 Ohm@100MHz,+/-25%,6A,10mOhm,G,SMD0805 | TAI-TECH ADVANCED ELECTRONICS CO., LTD. | HCB2012KF-220T60 |  | G |  |  |  |  |  |  |  |
|  |  |  |  |  | 87 | 72010Y600-174-G |  | FB,22 Ohm@100MHz,+/-25%,6A,8mOhm,G,SMD0805 | MAX ECHO TECHNOLOGIES CORP | BCMS201209A220 |  | G |  |  |  |  |  |  |  |
| Multi | ND |  | N | 88 | 88 | 72010A400-023-G |  | FB,80Ohm@100MHz,+/-25%,4A,10mOhm,G,SMD1206 | TAIYO ELECTRIC IND.CO.LTD | FBMJ3216HS800-T | 2 | G | L34,L36 |  |  |  |  |  |  |
|  |  |  |  |  | 88 | 72010A400-025-G |  | FB,Multilayer,10mOhm,80Ohm@100MHz,+/-25%,4A,,SMD1206,G | KEMET ELECTRONICS CORPORATION | Z1206C800APWST |  | G |  |  |  |  |  |  |  |
| Multi | ND |  | Y(2) | 89 | 89 | 72010MK00-015-G |  | FB,80 Ohm@100MHz,+/-25%,1.5A,70mOhm,G,SMD0402 | MURATA ELEC. NORTH AMERICA | BLM15PD800SN1D | 7 | G | L35,L37,L38,L39,L40,L41,L42 |  |  |  |  |  |  |
|  |  |  |  |  | 89 | 72010MK00-174-G |  | FB,80 Ohm@100MHz,+/-25%,1.5A,Multilayer,70mOhm,SMD0402,G | MAX ECHO TECHNOLOGIES CORP | ACMS100505A800 1.5A |  | G |  |  |  |  |  |  |  |
| Multi | Y | other | Y(2) | 90 | 90 | 720101M00-015-G |  | FB,600 Ohm@100MHz,+/-25%,200mA,650mOhm,G,SMD0603 | MURATA ELEC. NORTH AMERICA | BLM18BD601SN1D | 1 | G | L45 |  |  |  |  |  |  |
|  |  |  |  |  | 90 | 720103000-023-G |  | FB,600 Ohm@100MHz,+/-25%,250mA,600mOhm,G,SMD0603 | TAIYO ELECTRIC IND.CO.LTD | BK1608HM601-T |  | G |  |  |  |  |  |  |  |
| Single | ND |  | ND | 91 | 91 | 62111U700-024-G |  | ECAP,68uF,+/-20%,100V,105C,320mOhm,G,SMD12.5*13.5 | PANASONIC INDUSTRIAL CO.,LTD. | EEEFK2A680AQ | 6 | G | PSUCE1,PBACE1,PAACE1,PSUCE2,PBACE2,PAACE2 |  |  |  |  |  |  |
| Single | N |  | Y(1) | 92 | 92 | 62111QQ00-019-G |  | ECAP,82uF,+/-20%,100V,105C,G,SMD12.5*13.5,ESR<=280mOhm | NICHICON CORPORATION | UCZ2A820MNQ1MS | 8 | G | PBMCE1,PAMCE1,PBFCE2,PBECE2,PAFCE2,PAECE2,PBACE3,PAACE3 |  |  |  |  |  |  |
| Multi | N |  | Y(3) | 93 | 93 | 62120ER01-024-G |  | ECAP,SPEA,470uF,+/-20%,2.5V,105C,G,SMD2816,ESR<=3mOhm | PANASONIC INDUSTRIAL CO.,LTD. | EEFGX0E471R | 50 | G | PBNCE1,PANCE1,PBNCE2,PANCE2,PBECE3,PALCE3,PAFCE3,PAECE3,PBMCE4,PBFCE4,PBECE4,PBACE4,PAMCE4,PALCE4,PAFCE4,PAECE4,PAACE4,PBMCE5,PBFCE5,PBECE5,PBACE5,PAMCE5,PAFCE5,PAECE5,PAACE5,PBMCE6,PBFCE6,PBECE6,PBACE6,PAMCE6,PAFCE6,PAECE6,PAACE6,PBMCE7,PBLCE7,PBFCE7,PBACE7,PAMCE7,PAACE7,PBLCE8,PBACE8,PAACE8,PBACE9,PAACE9,PBACE10,PAACE10,PBACE11,PAACE11,PBACE12,PAACE12 |  |  |  |  |  |  |
|  |  |  |  |  | 93 | 62120ER00-025-G |  | ECAP,SPEA,Low ESR(LESR),470uF,+/-20%,2.5V,105_x0003_,3mOhm,SMD2816,G | KEMET ELECTRONICS CORPORATION | A720V477M2R5APE003 |  | G |  |  |  |  |  |  |  |
| Multi | Y |  | Y(1) | 94 | 94 | 62012RJ00-015-G |  | CAP,4.7uF,+/-10%,X6S,16V,G,SMD0603 | MURATA ELEC. NORTH AMERICA | GRM188C81C475K | 34 | G | PBMC1,PBFC1,PBEC1,PBAC1,PAMC1,PAFC1,PAEC1,PAAC1,PBMC2,PBFC2,PBEC2,PBAC2,PAMC2,PAFC2,PAEC2,PAAC2,PBMC22,PBFC22,PBEC22,PBAC22,PAMC22,PAFC22,PAEC22,PAAC22,PBMC450,PBFC450,PBEC450,PBAC450,PAMC450,PAFC450,PAEC450,PAAC450,PBAC452,PAAC452 |  |  |  |  |  |  |
|  |  |  |  |  | 94 | 62012RJ00-026-G |  | CAP,4.7uF,+/-10%,X6S,16V,G,SMD0603 | SAMSUNG SEMICONDUCTOR | CL10X475KO8NQNC |  | G |  |  |  |  |  |  |  |
|  |  |  |  |  | 94 | 62012RJ00-023-G |  | CAP,4.7uF,+/-10%,X6S,16V,G,SMD0603 | TAIYO ELECTRIC IND.CO.LTD | EMK107BC6475KA-T |  | G |  |  |  |  |  |  |  |
| Multi | ND | ND | Y(1) | 95 | 95 | 62010L800-015-G | - | CAP,1nF,+/-5%,NPO(C0G),50V,G,SMD0402 | MURATA ELEC. NORTH AMERICA | GRM1555C1H102J | 16 | G | PSPC5,PIPC5,PFPC5,PEPC5,PBMC5,PBAC5,PAMC5,PAAC5,PBAC23,PAAC23,PBMC95,PAMC95,PBFC451,PBEC451,PAFC451,PAEC451 |  |  |  |  |  |  |
|  |  |  |  |  | 95 | 62010L800-012-G |  | CAP,1nF,+/-5%,NPO(C0G),50V,G,SMD0402 | WALSIN TECHNOLOGY CORPORATION | 0402N102J500CT |  | G |  |  |  |  |  |  |  |
|  |  |  |  |  | 95 | 62010L800-026-G |  | CAP,1nF,+/-5%,NPO(C0G),50V,G,SMD0402 | SAMSUNG SEMICONDUCTOR | CL05C102JB5NNNC |  | G |  |  |  |  |  |  |  |
| Multi | N |  | Y(1) | 96 | 96 | 62011DQ00-015-G |  | CAP,27nF,+/-10%,X7R,25V,G,SMD0402 | MURATA ELEC. NORTH AMERICA | GRM155R71E273KA88D | 8 | G | PBMC6,PBFC6,PBEC6,PBAC6,PAMC6,PAFC6,PAEC6,PAAC6 |  |  |  |  |  |  |
|  |  |  |  |  | 96 | 620136P00-012-G |  | CAP,MLCC,27nF,+/-10%,X7R,25V,SMD0402,G | WALSIN TECHNOLOGY CORPORATION | 0402B273K250CT |  | G |  |  |  |  |  |  |  |
|  |  |  |  |  | 96 | 62011DQ00-011-G |  | CAP,MLCC,27nF,+/-10%,X7R,25V,SMD0402,G | YAGEO CORPORATION COMPONENT | CC0402KRX7R8BB273 |  | G |  |  |  |  |  |  |  |
| Multi | Y | 2 | Y(3) | 97 | 97 | 620102T00-015-G | - | CAP,150pF,+/-5%,NPO(C0G),50V,G,SMD0402 | MURATA ELEC. NORTH AMERICA | GRM1555C1H151J | 8 | G | PBMC7,PBFC7,PBEC7,PBAC7,PAMC7,PAFC7,PAEC7,PAAC7 |  |  |  |  |  |  |
|  |  |  |  |  | 97 | 620102T00-012-G |  | CAP,150pF,+/-5%,NPO(C0G),50V,G,SMD0402 | WALSIN TECHNOLOGY CORPORATION | 0402N151J500LT |  | G |  |  |  |  |  |  |  |
|  |  |  |  |  | 97 | 620102T00-026-G |  | CAP,150pF,+/-5%,NPO(C0G),50V,G,SMD0402 | SAMSUNG SEMICONDUCTOR | CL05C151JB5NNNC |  | G |  |  |  |  |  |  |  |
|  |  |  |  |  | 97 | 620102T00-023-G |  | CAP,150pF,+/-5%,NPO(C0G),50V,G,SMD0402 | TAIYO ELECTRIC IND.CO.LTD | UMK105CG151JV-F |  | G |  |  |  |  |  |  |  |
| Multi | ND | ND | Y(3) | 98 | 98 | 62010VD00-015-G |  | CAP,100nF,+/-10%,X7R,100V,G,SMD0603 | MURATA ELEC. NORTH AMERICA | GRM188R72A104K | 9 | G | PBEC11,PAFC11,PAEC11,PBMC12,PBFC12,PBAC12,PAMC12,PAAC12,PHAC14 |  |  |  |  |  |  |
|  |  |  |  |  | 98 | 62010VD00-026-G |  | CAP,100nF,+/-10%,X7R,100V,G,SMD0603 | SAMSUNG SEMICONDUCTOR | CL10B104KC8NNNC |  | G |  |  |  |  |  |  |  |
| Multi | N |  | Y(1) | 99 | 99 | 62011J601-015-G |  | CAP,2.2uF,+/-10%,X7R,100V,G,SMD1210 | MURATA ELEC. NORTH AMERICA | GRM32ER72A225K | 42 | G | PSUC1,PSUC2,PBMC13,PBFC13,PBEC13,PBAC13,PAMC13,PAFC13,PAEC13,PAAC13,PBMC14,PBFC14,PBEC14,PBAC14,PAMC14,PAFC14,PAEC14,PAAC14,PBMC15,PBFC15,PBEC15,PBAC15,PAMC15,PAFC15,PAEC15,PAAC15,PBAC16,PAAC16,PBEC17,PBAC17,PAAC17,PBAC18,PAAC18,PBAC19,PAAC19,PBAC20,PAFC20,PAAC20,PBMC21,PBFC21,PAMC21,PAEC21 |  |  |  |  |  |  |
|  |  |  |  |  | 99 | 62011J600-026-G |  | CAP,2.2uF,+/-10%,X7R,100V,G,SMD1210 | SAMSUNG SEMICONDUCTOR | CL32B225KCJSNNE |  | G |  |  |  |  |  |  |  |
| Multi | Y | 2 | Y(3) | 100 | 100 | 620107L00-015-G | - | CAP,2.2nF,+/-10%,X7R,50V,G,SMD0402 | MURATA ELEC. NORTH AMERICA | GRM155R71H222K | 16 | G | PSRC2,PSPC12,PIPC12,PFPC12,PEPC12,PSIC18,PETC18,PERC18,PBFC25,PBEC25,PAFC25,PBMC26,PBAC26,PAMC26,PAAC26,PAEC516 |  |  |  |  |  |  |
|  |  |  |  |  | 100 | 620107L00-012-G |  | CAP,2.2nF,+/-10%,X7R,50V,G,SMD0402 | WALSIN TECHNOLOGY CORPORATION | 0402B222K500CT |  | G |  |  |  |  |  |  |  |
|  |  |  |  |  | 100 | 620107L00-026-G |  | CAP,2.2nF,+/-10%,X7R,50V,G,SMD0402 | SAMSUNG SEMICONDUCTOR | CL05B222KB5NNNC |  | G |  |  |  |  |  |  |  |
|  |  |  |  |  | 100 | 620107L03-023-G |  | CAP,2.2nF,+/-10%,X7R,50V,G,SMD0402 | TAIYO ELECTRIC IND.CO.LTD | UMK105B7222KV-F |  | G |  |  |  |  |  |  |  |
| Multi | ND | ND | Y(1) | 101 | 101 | 62011DA00-015-G | - | CAP,1uF,+/-10%,X7R,100V,G,SMD1206 | MURATA ELEC. NORTH AMERICA | GRM31CR72A105K | 6 | G | PBMC27,PBAC27,PAMC27,PAAC27,PBAC111,PAAC111 |  |  |  |  |  |  |
|  |  |  |  |  | 101 | 62011DA00-023-G |  | CAP,1uF,+/-10%,X7R,100V,G,SMD1206 | TAIYO ELECTRIC IND.CO.LTD | HMK316B7105KL-T |  | G |  |  |  |  |  |  |  |
|  |  |  |  |  | 101 | 62011DA00-026-G |  | CAP,1uF,+/-10%,X7R,100V,G,SMD1206 | SAMSUNG SEMICONDUCTOR | CL31B105KCHNNNE |  | G |  |  |  |  |  |  |  |
|  |  |  |  |  | 101 | 62011DA02-015-G |  | CAP,1uF,+/-10%,X7R,100V,G,SMD1206 | MURATA ELEC. NORTH AMERICA | GRM31CR72A105KA01K |  | G |  |  |  |  |  |  |  |
| Multi | ND | ND | ND | 102 | 102 | 620107500-015-G | - | CAP,3.9nF,+/-10%,X7R,50V,G,SMD0402 | MURATA ELEC. NORTH AMERICA | GRM155R71H392K | 2 | G | PBAC125,PAAC125 |  |  |  |  |  |  |
|  |  |  |  |  | 102 | 620107500-026-G |  | CAP,3.9nF,+/-10%,X7R,50V,G,SMD0402 | SAMSUNG SEMICONDUCTOR | CL05B392KB5NNNC |  | G |  |  |  |  |  |  |  |
|  |  |  |  |  | 102 | 620107500-011-G |  | CAP,3.9nF,+/-10%,X7R,50V,G,SMD0402 | YAGEO CORPORATION COMPONENT | CC0402KRX7R9BB392 |  | G |  |  |  |  |  |  |  |
|  |  |  |  |  | 102 | 620107500-023-G |  | CAP,3.9nF,+/-10%,X7R,50V,G,SMD0402 | TAIYO ELECTRIC IND.CO.LTD | UMK105B7392KV-F |  | G |  |  |  |  |  |  |  |
| Multi | N |  | Y(3) | 103 | 103 | 620127602-015-G |  | CAP,47uF,+/-20%,X6S,4V,G,SMD0805 | MURATA ELEC. NORTH AMERICA | GRM21BC80G476M | 684 | G | PBNC18,PANC18,PBNC19,PANC19,PUAC20,PSAC20,PRAC20,PQAC20,PPAC20,PIAC20,PFAC20,PEAC20,PBNC20,PANC20,PUAC21,PSAC21,PRAC21,PQAC21,PPAC21,PIAC21,PFAC21,PEAC21,PBNC21,PANC21,PUAC22,PSAC22,PRAC22,PQAC22,PPAC22,PIAC22,PFAC22,PEAC22,PBNC22,PANC22,PUAC23,PSAC23,PRAC23,PQAC23,PPAC23,PIAC23,PFAC23,PEAC23,PBNC23,PANC23,PUAC24,PSAC24,PRAC24,PQAC24,PPAC24,PIAC24,PFAC24,PEAC24,PUAC25,PSAC25,PRAC25,PQAC25,PPAC25,PIAC25,PFAC25,PEAC25,PALC25,PALC26,PALC27,PALC28,PALC29,PALC30,PALC31,PALC32,PALC33,PALC34,PBLC45,PBLC46,PBLC47,PBLC48,PBLC49,PBLC50,PBLC51,PBLC52,PBLC53,PBLC63,PBMC73,PAMC73,PBMC74,PAMC74,PBMC75,PAMC75,PBMC76,PAMC76,PBMC77,PAMC77,PBMC78,PAMC78,PBMC79,PAMC79,PBMC80,PAMC80,PBMC81,PAMC81,PBMC82,PAMC82,PBMC83,PAMC83,PBMC84,PAMC84,PBMC85,PAMC85,PBMC86,PAMC86,PBMC87,PAMC87,PBMC88,PAMC88,PBMC89,PAMC89,PBMC90,PAMC90,PBMC91,PAMC91,PBMC92,PAMC92,PBMC93,PAMC93,PBMC94,PAMC94,PBMC96,PAMC96,PBMC97,PAMC97,PBMC98,PAMC98,PBMC99,PAMC99,PBMC100,PAMC100,PBMC101,PAMC101,PBMC102,PAMC102,PBMC103,PAMC103,PBAC167,PAAC167,PBAC168,PAAC168,PBAC169,PAAC169,PBAC170,PAAC170,PBAC171,PAAC171,PBAC172,PAAC172,PBAC173,PAAC173,PBAC174,PAAC174,PBAC175,PAAC175,PBAC176,PAAC176,PBAC177,PAAC177,PBAC178,PAAC178,PBAC179,PAAC179,PBAC180,PAAC180,PBAC181,PAAC181,PBAC182,PAAC182,PBAC183,PAAC183,PBAC184,PAAC184,PBAC185,PAAC185,PBAC186,PAAC186,PBAC187,PAAC187,PBAC188,PAAC188,PBAC189,PAAC189,PBAC190,PAAC190,PBAC191,PAAC191,PBAC192,PAAC192,PBAC193,PAAC193,PBAC194,PAAC194,PBAC195,PAAC195,PBAC196,PAAC196,PBAC197,PAAC197,PBAC198,PAAC198,PBAC199,PAAC199,PBAC200,PAAC200,PBAC201,PAAC201,PBAC202,PAAC202,PBAC203,PAAC203,PBAC204,PAAC204,PBAC205,PAAC205,PBAC206,PAAC206,PBAC207,PAAC207,PBAC208,PAAC208,PBAC209,PAAC209,PBAC210,PAAC210,PBAC211,PAAC211,PBAC212,PAAC212,PBAC213,PAAC213,PBAC214,PAAC214,PBAC215,PAAC215,PBAC216,PAAC216,PBAC217,PAAC217,PBAC218,PAAC218,PBAC219,PAAC219,PBAC220,PAAC220,PBAC221,PAAC221,PBAC222,PAAC222,PBAC223,PAAC223,PBAC224,PAAC224,PBAC225,PAAC225,PBAC226,PAAC226,PBAC227,PAAC227,PBAC228,PAAC228,PBAC229,PAAC229,PBAC230,PAAC230,PBAC231,PAAC231,PBAC232,PAAC232,PBAC233,PAAC233,PBAC234,PAAC234,PBAC235,PAAC235,PBAC236,PAAC236,PBAC237,PAAC237,PBAC238,PAAC238,PBAC239,PAAC239,PBAC240,PAAC240,PBAC241,PAAC241,PBAC242,PAAC242,PBAC243,PAAC243,PBAC244,PAAC244,PBAC245,PAAC245,PBAC246,PAAC246,PBFC300,PBEC300,PAFC300,PAEC300,PBFC301,PBEC301,PAFC301,PAEC301,PBFC302,PBEC302,PAFC302,PAEC302,PBFC303,PBEC303,PAFC303,PAEC303,PBFC304,PBEC304,PAFC304,PAEC304,PBFC305,PBEC305,PAFC305,PAEC305,PBFC306,PBEC306,PAFC306,PAEC306,PBFC307,PBEC307,PAFC307,PAEC307,PBFC308,PBEC308,PAFC308,PAEC308,PBFC309,PBEC309,PAFC309,PAEC309,PBFC310,PBEC310,PAFC310,PAEC310,PBFC311,PBEC311,PAFC311,PAEC311,PBFC312,PBEC312,PAFC312,PAEC312,PBFC313,PBEC313,PAFC313,PAEC313,PBFC314,PBEC314,PAFC314,PAEC314,PBFC315,PBEC315,PAFC315,PAEC315,PBFC316,PBEC316,PAFC316,PAEC316,PBFC317,PBEC317,PAFC317,PAEC317,PBFC318,PBEC318,PAFC318,PAEC318,PBFC319,PBEC319,PAFC319,PAEC319,PBFC320,PBEC320,PAFC320,PAEC320,PBFC321,PBEC321,PAFC321,PAEC321,PBFC322,PBEC322,PAFC322,PAEC322,PBFC323,PBEC323,PAFC323,PAEC323,PBFC324,PBEC324,PAFC324,PAEC324,PBFC325,PBEC325,PAFC325,PAEC325,PBFC326,PBEC326,PAFC326,PAEC326,PBFC327,PBEC327,PAFC327,PAEC327,PBFC328,PBEC328,PAFC328,PAEC328,PBFC329,PBEC329,PAFC329,PAEC329,PBFC330,PBEC330,PAFC330,PAEC330,PBFC331,PBEC331,PAFC331,PAEC331,PBFC332,PBEC332,PAFC332,PAEC332,PBFC333,PBEC333,PAFC333,PAEC333,PBFC334,PBEC334,PAFC334,PAEC334,PBFC335,PBEC335,PAFC335,PAEC335,PBFC336,PBEC336,PAFC336,PAEC336,PBFC337,PBEC337,PAFC337,PAEC337,PBFC338,PBEC338,PAFC338,PAEC338,PBFC339,PBEC339,PAFC339,PAEC339,PBFC340,PBEC340,PAFC340,PAEC340,PBFC341,PBEC341,PAFC341,PAEC341,PBFC342,PBEC342,PAFC342,PAEC342,PBFC343,PBEC343,PAFC343,PAEC343,PBFC344,PBEC344,PAFC344,PAEC344,PBFC345,PBEC345,PAFC345,PAEC345,PBFC346,PBEC346,PAFC346,PAEC346,PBFC347,PBEC347,PAFC347,PAEC347,PBFC348,PBEC348,PAFC348,PAEC348,PBFC349,PBEC349,PAFC349,PAEC349,PBFC350,PBEC350,PAFC350,PAEC350,PBFC351,PBEC351,PAFC351,PAEC351,PBFC352,PBEC352,PAFC352,PAEC352,PBFC353,PBEC353,PAFC353,PAEC353,PBFC354,PBEC354,PAFC354,PAEC354,PBFC355,PBEC355,PAFC355,PAEC355,PBFC356,PBEC356,PAFC356,PAEC356,PBFC357,PBEC357,PAFC357,PAEC357,PBFC358,PBEC358,PAFC358,PAEC358,PBFC359,PBEC359,PAFC359,PAEC359,PBFC360,PBEC360,PAFC360,PAEC360,PBFC361,PBEC361,PAFC361,PAEC361,PBFC362,PBEC362,PAFC362,PAEC362,PBFC363,PBEC363,PAFC363,PAEC363,PBFC364,PBEC364,PAFC364,PAEC364,PBFC365,PBEC365,PAFC365,PAEC365,PBFC366,PBEC366,PAFC366,PAEC366,PBFC367,PBEC367,PAFC367,PAEC367,PBFC368,PBEC368,PAFC368,PAEC368,PBFC369,PBEC369,PAFC369,PAEC369,PBFC370,PBEC370,PAFC370,PAEC370,PBFC371,PBEC371,PAFC371,PAEC371,PBFC372,PBEC372,PAFC372,PAEC372,PBFC373,PBEC373,PAFC373,PAEC373,PBFC374,PBEC374,PAFC374,PAEC374,PBFC375,PBEC375,PAFC375,PAEC375,PBFC376,PBEC376,PAFC376,PAEC376,PBFC377,PBEC377,PAFC377,PAEC377,PBFC378,PBEC378,PAFC378,PAEC378,PBFC379,PBEC379,PAFC379,PAEC379,PBFC380,PBEC380,PAFC380,PAEC380,PBFC381,PBEC381,PAFC381,PAEC381,PBFC382,PBEC382,PAFC382,PAEC382,PBFC383,PBEC383,PAFC383,PAEC383,PBFC384,PBEC384,PAFC384,PAEC384,PBFC385,PBEC385,PAFC385,PAEC385,PBFC386,PBEC386,PAFC386,PAEC386,PBFC387,PBEC387,PAFC387,PAEC387,PBFC388,PBEC388,PAFC388,PAEC388,PBFC389,PBEC389,PAFC389,PAEC389,PBFC390,PBEC390,PAFC390,PAEC390,PBFC391,PBEC391,PAFC391,PAEC391,PBFC392,PBEC392,PAFC392,PAEC392,PBFC393,PBEC393,PAFC393,PAEC393,PBFC394,PBEC394,PAFC394,PAEC394,PBFC395,PBEC395,PAFC395,PAEC395 |  |  |  |  |  |  |
|  |  |  |  |  | 103 | 620127600-023-G |  | CAP,47uF,+/-20%,X6S,4V,G,SMD0805 | TAIYO ELECTRIC IND.CO.LTD | AMK212BC6476MG-T |  | G |  |  |  |  |  |  |  |
|  |  |  |  |  | 103 | 620127600-026-G |  | CAP,47uF,+/-20%,X6S,4V,G,SMD0805 | SAMSUNG SEMICONDUCTOR | CL21X476MRYNNNE |  | G |  |  |  |  |  |  |  |
| Multi |  |  | Y(3) | 104 | 104 | 62010GS00-015-G |  | CAP,15nF,+/-10%,X7R,25V,G,SMD0603 | MURATA ELEC. NORTH AMERICA | GRM188R71E153K | 8 | G | PBMC400,PBFC400,PBEC400,PBAC400,PAMC400,PAFC400,PAEC400,PAAC400 |  |  |  |  |  |  |
|  |  |  |  |  | 104 | 620106B00-012-G |  | CAP,15nF,+/-10%,X7R,25V,G,SMD0603 | WALSIN TECHNOLOGY CORPORATION | 0603B153K250CT |  | G |  |  |  |  |  |  |  |
|  |  |  |  |  | 104 | 620106B00-026-G |  | CAP,15nF,+/-10%,X7R,25V,G,SMD0603 | SAMSUNG SEMICONDUCTOR | CL10B153KA8NNNC |  | G |  |  |  |  |  |  |  |
| Multi | N |  | N | 105 | 105 | 520103B00-185-G |  | Diode,Rectifier&Switching,MMBD1205,100V,200mA,G,SOT-23-3,SMD | FAIRCHILD SEMICONDUCTOR CORP | MMBD1205 | 8 | G | PBMD1,PBFD1,PBED1,PBAD1,PAMD1,PAFD1,PAED1,PAAD1 |  |  |  |  |  |  |
|  |  |  |  |  | 105 | 52010A100-237-G |  | Diode,Rectifier&Switching,100V,200mA,G,SOT-23-3,SMD | DIODES INCORPORATION | MMBD3004A-7-F |  | G |  |  |  |  |  |  |  |
| Single | ND |  | N | 106 | 106 | 52030TQ00-237-G |  | Diode,Schottky,BAS40-06-7-F,40V,200mA,G,SOT-23-3,SMD | DIODES INCORPORATION | BAS40-06-7-F | 8 | G | PBMD3,PBFD3,PBED3,PBAD3,PAMD3,PAFD3,PAED3,PAAD3 |  |  |  |  |  |  |
| Multi | ND | ND | Y(1) | 107 | 107 | 730100M00-086-G | - | Fuse,Very fast acting,125V,10A,G,SMD | LITTELFUSE FAR EAST PTE LTD | 0451010.MRL | 4 | G | PSUFS1,PBAFS1,PAAFS1,PSUFS2 |  |  |  |  |  |  |
|  |  |  |  |  | 107 | 730109A00-088-G |  | Fuse,Fast acting,125V,10A,G,SMD | COOPER BUSSMANN, INC. | CB61F10A-TR2 |  | G |  |  |  |  |  |  |  |
| Multi | N |  | N | 108 | 108 | 63035NQ00-029-G |  | IND,0.1uH@100KHz,+/-20%,11.5A,6mOhm,SHLD,G,SMD | VISHAY ENTER TECHNO LOGY.INC | IHLP1616ABERR10M01 | 18 | G | PBML1,PBAL1,PAML1,PAAL1,PBFL2,PBEL2,PAFL2,PAEL2,PBML3,PBFL3,PBEL3,PBAL3,PAML3,PAFL3,PAEL3,PAAL3,PBAL5,PAAL5 |  |  |  |  |  |  |
|  |  |  |  |  | 108 | 63032QU00-034-G |  | Coil Ind,Shielded(SHLD),100nH@100KHz,+/-20%,12A,4mOhm,SMD,4.15*4.0*1.8,G | CYNTEC CO. LTD | PCMB042T-R10MS |  | G |  |  |  |  |  |  |  |
| Single | ND |  | N | 109 | 109 | 63035R700-57M-G |  | IND,375nH@1MHz,+/-5%,16A,1.15mOhm,SHLD,G,SMD | Eaton Corporation | CTX01-19603-R | 2 | G | PBAL2,PAAL2 |  |  |  |  |  |  |
| Multi | ND | ND | N | 110 | 110 | 510201900-185-G |  | TRANS P,MMBT3906,40V,0.2A,G,SOT23-3,SMD | FAIRCHILD SEMICONDUCTOR CORP | MMBT3906 | 16 | G | PBMQ1,PBFQ1,PBEQ1,PBAQ1,PAMQ1,PAFQ1,PAEQ1,PAAQ1,PBMQ2,PBFQ2,PBEQ2,PBAQ2,PAMQ2,PAFQ2,PAEQ2,PAAQ2 |  |  |  |  |  |  |
|  |  |  |  |  | 110 | 510201900-031-G |  | TRANS P,MMBT3906,40V,0.2A,G,SOT23-3,SMD | NXP SEMICONDUCTORS | MMBT3906 |  | G |  |  |  |  |  |  |  |
|  |  |  |  |  | 110 | 510200600-237-G |  | TRANS P,MMBT3906-7-F,40V,0.2A,G,SOT23-3,SMD | DIODES INCORPORATION | MMBT3906-7-F |  | G |  |  |  |  |  |  |  |
| Multi | N |  | N | 111 | 111 | 51032DL00-237-G |  | MOS N,DMT10H014LSS-13,100V,8.9A,15m@10V,G,SO-8,SMD | DIODES INCORPORATION | DMT10H014LSS-13 | 8 | G | PBMQ10,PBAQ10,PAMQ10,PAAQ10,PBFQ11,PBEQ11,PAFQ11,PAEQ11 |  |  |  |  |  |  |
|  |  |  |  |  | 111 | 51032FL00-029-G |  | MOS N,Si4190ADY-T1-GE3,100V,18.4A,8.8m@10V,G,SO-8,SMD | VISHAY ENTER TECHNO LOGY.INC | Si4190ADY-T1-GE3 |  | G |  |  |  |  |  |  |  |
| Multi | ND | ND | Y(3) | 112 | 112 | 510100W00-237-G | - | TRANS N,MMBT3904-7-F,40V,0.2A,G,SOT23-3,SMD | DIODES INEORPORATION | MMBT3904-7-F | 11 | G | Q8,PHAQ8,PBMQ11,PBAQ11,PAMQ11,PAAQ11,PBFQ12,PBEQ12,PAFQ12,PAEQ12,Q85 |  |  |  |  |  |  |
|  |  |  |  |  | 112 | 510100500-031-G |  | TRANS N,PMBT3904,40V,0.2A,G,SOT23-3,SMD | NXP SEMICONDUCTORS | PMBT3904 |  | G |  |  |  |  |  |  |  |
|  |  |  |  |  | 112 | 510101700-185-G |  | TRANS N,MMBT3904,40V,0.2A,G,SOT23-3,SMD | FAIRCHILD SEMICONDUCTOR CORP | MMBT3904 |  | G |  |  |  |  |  |  |  |
|  |  |  |  |  | 112 | 510100800-223-G |  | TRANS N,MMBT3904LT1G,40V,0.2A,G,SOT23-3,SMD | ON SEMICONDUCTOR CORP | MMBT3904LT1G |  | G |  |  |  |  |  |  |  |
| Multi | ND | ND | N | 113 | 113 | 510302R00-185-G |  | MOS N,BSS138,50V,0.22A,6ohm@4.5V,G,SOT23-3,SMD | FAIRCHILD SEMICONDUCTOR CORP | BSS138 | 8 | G | PBFQ10,PBEQ10,PAFQ10,PAEQ10,PBMQ12,PBAQ12,PAMQ12,PAAQ12 |  |  |  |  |  |  |
|  |  |  |  |  | 113 | 510309C00-237-G |  | MOS N,BSS138-7-F,50V,0.2A,3.5ohm@10V,G,SOT23-3,SMD | DIODES INCORPORATION | BSS138-7-F |  | G |  |  |  |  |  |  |  |
|  |  |  |  |  | 113 | 510301D00-223-G |  | MOS N,BSS138LT1G,50V,0.2A,3.5ohm@5V,G,SOT23-3,SMD | ON SEMICONDUCTOR CORP | BSS138LT1G |  | G |  |  |  |  |  |  |  |
| Multi | N | ND | Y(4) | 114 | 114 | 610108300-017-G | - | RES,0 Ohm,+/-5%,1/10W,G,SMD0603 | KOA SPEER ELECTRONICS, INC. | RK73Z1JTTD | 108 | G | PUAR1,PSIR1,PSAR1,PRAR1,PQAR1,PPAR1,PIAR1,PFAR1,PETR1,PERR1,PEAR1,PBMR1,PBFR1,PBER1,PBAR1,PAMR1,PAFR1,PAER1,PAAR1,PUAR3,PSIR3,PSAR3,PRAR3,PQAR3,PPAR3,PIAR3,PFAR3,PETR3,PERR3,PEAR3,PUAR9,PSIR9,PSAR9,PRAR9,PQAR9,PPAR9,PIAR9,PFAR9,PETR9,PERR9,PEAR9,PBNR10,PANR10,PBNR13,PANR13,PBAR66,PBMR68,PAMR70,PBER71,PAFR71,PAER71,PAAR71,PBFR72,PBMR78,PAMR78,R133,R142,R153,R163,R174,R184,R196,R205,R217,R226,R238,R247,R258,R268,R280,R289,PBER308,PBFR400,PBAR400,PAFR400,PAER400,PAAR400,R488,R497,R508,R518,R529,R539,R551,R560,R572,R581,R593,R602,R614,R623,R635,R644,R1028,R1742,R1743,R1744,R1747,R1748,R1749,R1755,R1761,R1762,R1763,R1764,R1765,R1766,R1767 |  |  |  |  |  |  |
|  |  |  |  |  | 114 | 610108300-012-G |  | RES,0 Ohm,+/-5%,1/10W,G,SMD0603 | WALSIN TECHNOLOGY CORPORATION | WR06X000PTL |  | G |  |  |  |  |  |  |  |
|  |  |  |  |  | 114 | 610108300-011-G |  | RES,0 Ohm,+/-5%,1/10W,G,SMD0603 | YAGEO CORPORATION COMPONENT | RC0603JR-070RL |  | G |  |  |  |  |  |  |  |
|  |  |  |  |  | 114 | 610108300-044-G |  | RES,0 Ohm,+/-5%,1/10W,G,SMD0603 | TA-I TECHNOLOGY CO., LTD | RM06JTN0 |  | G |  |  |  |  |  |  |  |
|  |  |  |  |  | 114 | 610108300-024-G |  | RES,0 Ohm,+/-5%,1/10W,G,SMD0603 | PANASONIC INDUSTRIAL CO.,LTD. | ERJ3GEY0R00V |  | G |  |  |  |  |  |  |  |
| Multi | N | ND | Y(4) | 115 | 115 | 610107A00-017-G | - | RES,0 Ohm,+/-5%,1/16W,G,SMD0402 | KOA SPEER ELECTRONICS, INC. | RK73Z1ETTP | 717 | G | R1,R2,PSTR2,PSPR2,PSLR2,PSFR2,PSER2,PSDR2,PQPR2,PIPR2,PFPR2,PEPR2,PEER2,PEDR2,PBFR2,PBER2,PBAR2,PAFR2,PAER2,PAAR2,PBNR3,PBER3,PBAR3,PANR3,PAER3,PAAR3,PBNR4,PBFR4,PBAR4,PANR4,PAFR4,PAAR4,PBAR5,PAAR5,R6,PAMR6,PAAR6,R7,PSPR7,PIPR7,PFPR7,PEPR7,PBFR7,PAER7,PSRR8,PSPR8,PSLR8,PSFR8,PSDR8,PQPR8,PIPR8,PFRR8,PFPR8,PEPR8,PEER8,PEDR8,PAFR8,PAER8,PSTR9,PSLR9,PSFR9,PSER9,PSDR9,PQPR9,PFRR9,PEER9,PEDR9,PBER9,PBAR9,PAMR9,PHAR10,PBFR10,PAAR10,PBMR11,PBER11,PAFR11,PUAR12,PSIR12,PSAR12,PRAR12,PQAR12,PPAR12,PIAR12,PHAR12,PFAR12,PETR12,PERR12,PEAR12,PBNR12,PANR12,PBER13,PAAR13,PUAR14,PSRR14,PSPR14,PSAR14,PRAR14,PQAR14,PPAR14,PIPR14,PIAR14,PFPR14,PFAR14,PEPR14,PEAR14,PBMR14,PBFR14,PBAR14,PAFR14,PUAR15,PSTR15,PSRR15,PSLR15,PSFR15,PSER15,PSDR15,PSAR15,PRAR15,PQPR15,PQAR15,PPAR15,PIAR15,PFRR15,PFAR15,PEER15,PEDR15,PEAR15,PBFR15,PBER15,PBAR15,PAFR15,PAER15,PAAR15,PSIR16,PETR16,PERR16,PBMR16,PBAR16,PAMR16,PAER16,PALR17,PSTR18,PSLR18,PSFR18,PSER18,PSDR18,PQPR18,PFRR18,PEER18,PEDR18,PBMR18,PBFR18,PBER18,PBAR18,PAMR18,PAFR18,PAER18,PAAR18,PBLR19,PBNR20,PANR20,PSRR22,PSPR22,PIPR22,PFPR22,PEPR22,PBMR22,PBFR22,PBER22,PBAR22,PAMR22,PAFR22,PAER22,PAAR22,PHAR24,PHAR25,PBMR25,PBFR25,PBER25,PBAR25,PAMR25,PAFR25,PAER25,PAAR25,PBMR28,PBFR28,PBER28,PBAR28,PAMR28,PAFR28,PAER28,PAAR28,R29,R30,PBMR30,PBFR30,PBER30,PBAR30,PAMR30,PAFR30,PAER30,PAAR30,PHAR31,PHAR32,PBMR32,PBFR32,PBER32,PBAR32,PAMR32,PAFR32,PAER32,PAAR32,PHAR33,PBMR33,PBFR33,PBER33,PBAR33,PAMR33,PAFR33,PAER33,PAAR33,PHAR34,PBMR35,PBFR35,PBER35,PBAR35,PAMR35,PAFR35,PAER35,PAAR35,PBMR36,PBFR36,PBER36,PBAR36,PAMR36,PAFR36,PAER36,PAAR36,PBMR38,PBFR38,PBER38,PBAR38,PAMR38,PAFR38,PAER38,PAAR38,PBMR39,PBAR39,PAMR39,PAAR39,PBMR42,PBFR42,PBER42,PBAR42,PAMR42,PAFR42,PAER42,PAAR42,PBMR46,PAMR46,PBMR56,PBFR56,PBER56,PBAR56,PAMR56,PAFR56,PAER56,PAAR56,PBMR66,PAMR67,PAMR68,PAAR68,PBAR69,PAAR69,R70,PBMR70,PBAR70,R71,R72,PBAR72,PAAR72,R73,R74,R75,PAFR77,PAER77,PBFR78,PBER78,PAFR78,PAER78,R79,PBMR79,PBFR79,PBER79,PAMR79,PAFR79,PAER79,R80,PBFR80,R81,PBER81,PBAR81,PAFR81,PAER81,PAAR81,R82,PBFR82,PBER82,PAER82,R83,R84,R85,R86,R87,PBMR87,PBER87,PAMR87,PBER89,PBAR89,PAFR89,PAER89,PAAR89,PBFR90,PBER93,PAFR93,PAER93,PBFR94,PBER96,PAFR96,PAER96,PBFR97,PBAR101,PAAR101,PBMR103,PAMR103,PBMR104,PAMR104,PBER105,PAFR105,PAER105,PBFR106,PBER106,PAFR106,PAER106,PBFR107,PBMR110,PBAR110,PAMR110,PAAR110,PBMR111,PAMR111,PBER112,PAFR112,PAER112,PBFR113,PBER113,PAFR113,PAER113,PBFR114,PBMR115,PAMR115,PBMR116,PBAR116,PAMR116,PAAR116,PBER117,PBAR117,PAFR117,PAER117,PAAR117,PBFR118,PBER118,PAFR118,PAER118,PBFR119,PBAR121,PAAR121,PBAR122,PAAR122,PBFR302,PBER302,PBAR302,PAFR302,PAER302,PAAR302,R303,PBMR303,PBFR303,PBER303,PBAR303,PAMR303,PAFR303,PAER303,PAAR303,R306,R308,PBMR308,PBAR308,PAMR308,PAAR308,R309,PBMR309,PBAR309,PAMR309,PAAR309,PBFR310,PAFR310,PAER310,R311,PBER311,R312,PBFR312,PAFR312,PAER312,R313,PBER313,R314,R315,R316,R317,R320,R321,R322,R323,R324,R325,R326,R331,R363,R364,R368,R369,R414,R415,R428,R429,R430,R431,R433,R434,R437,R438,R439,R440,R467,R473,R474,R477,R478,R479,PSUR500,PBNR500,PBMR500,PBFR500,PBER500,PANR500,PAMR500,PAFR500,PAER500,PAAR500,PSUR501,PBNR501,PBMR501,PBFR501,PBER501,PANR501,PAMR501,PAFR501,PAER501,PAAR501,PBAR502,PBAR503,PBFR514,PBER514,PAFR514,PBFR515,PBER515,PAFR515,PAER515,PBFR516,PBER516,PAFR516,PAER516,PAER517,PBMR607,PBAR607,PAMR607,PAAR607,PBMR608,PBAR608,PAMR608,PAAR608,R670,R671,R674,R677,R717,R722,R723,R724,R726,R728,R744,R745,R747,R750,R754,R757,R760,R761,R768,R785,R798,R802,R810,R812,R813,R824,R826,R895,R896,R899,R900,R909,R911,R918,R919,R921,R923,R924,R926,R928,R930,R931,R941,R946,R947,R951,R952,R973,R974,R979,R987,R1004,R1005,R1073,R1082,R1086,R1099,R1100,R1116,R1117,R1130,R1131,R1132,R1133,R1134,R1143,R1145,R1146,R1158,R1160,R1166,R1167,R1168,R1170,R1177,R1178,R1179,R1180,R1182,R1187,R1188,R1191,R1192,R1194,R1200,R1201,R1203,R1204,R1207,R1208,R1214,R1215,R1216,R1228,R1233,R1235,R1236,R1238,R1241,R1242,R1243,R1244,R1245,R1246,R1247,R1248,R1249,R1250,R1259,R1260,R1281,R1282,R1283,R1284,R1285,R1286,R1289,R1290,R1291,R1292,R1293,R1297,R1321,R1322,R1330,R1339,R1344,R1360,R1362,R1369,R1370,R1372,R1373,R1375,R1376,R1406,R1407,R1432,R1433,R1434,R1435,R1436,R1437,R1438,R1439,R1442,R1443,R1445,R1473,R1478,R1491,R1496,R1497,R1501,R1503,R1510,R1514,R1519,R1522,R1527,R1528,R1531,R1532,R1549,R1552,R1555,R1556,R1599,R1600,R1720,R1721,R1722,R1724,R1725,R1752,R1753,R1776,R1787,R1788,R1803,R1804,R1805,R1806,R1807,R1808,R1809,R1810,R1812,R1813,R1814,R1825,R1826,R1832,R1833,R1835,R1837,R1840,R1841,R1842,R1843,R1848,R1849,R2045,R2046,R2047,R2048,R2049,R2050,R2051,R2052,PSPR3001,PIPR3001,PFPR3001,PEPR3001,PSPR3002,PIPR3002,PFPR3002,PEPR3002,PSRR3003,PSPR3003,PIPR3003,PFPR3003,PEPR3003,PSRR3005,PSRR3008 |  |  |  |  |  |  |
|  |  |  |  |  | 115 | 610107A00-012-G |  | RES,0 Ohm,+/-5%,1/16W,G,SMD0402 | WALSIN TECHNOLOGY CORPORATION | WR04X000PTL |  | G |  |  |  |  |  |  |  |
|  |  |  |  |  | 115 | 610107A00-011-G |  | RES,0 Ohm,+/-5%,1/16W,G,SMD0402 | YAGEO CORPORATION COMPONENT | RC0402JR-070RL |  | G |  |  |  |  |  |  |  |
|  |  |  |  |  | 115 | 610107A00-044-G |  | RES,0 Ohm,+/-5%,1/16W,G,SMD0402 | TA-I TECHNOLOGY CO., LTD | RM04JTN0 |  | G |  |  |  |  |  |  |  |
|  |  |  |  |  | 115 | 610107A00-024-G |  | RES,0 Ohm,+/-5%,1/16W,G,SMD0402 | PANASONIC INDUSTRIAL CO.,LTD. | ERJ2GE0R00X |  | G |  |  |  |  |  |  |  |
|  |  |  |  |  | 115 | 610107A00-029-G |  | RES,0 Ohm,+/-5%,1/16W,G,SMD0402 | VISHAY ENTER TECHNO LOGY.INC | CRCW04020000Z0ED |  | G |  |  |  |  |  |  |  |
| Multi | ND | ND | Y(4) | 116 | 116 | 61010PS00-017-G | - | RES,200KOhm,+/-1%,1/16W,G,SMD0402 | KOA SPEER ELECTRONICS, INC. | RK73H1ETTP2003F | 52 | G | PBER7,PAMR7,PBAR8,PAMR8,PAFR9,PAAR9,PAFR10,PAER10,PBAR11,PAER11,PBFR12,PBAR12,PAAR12,PBMR13,PBFR13,PBER14,PAAR14,PBMR15,PBMR17,PBFR17,PBER17,PBAR17,PAMR17,PAFR17,PAER17,PAAR17,PBMR21,PBFR21,PBER21,PBAR21,PAMR21,PAFR21,PAER21,PAAR21,PBMR24,PBFR24,PBER24,PBAR24,PAMR24,PAFR24,PAER24,PAAR24,PBMR27,PBFR27,PBER27,PBAR27,PAMR27,PAFR27,PAER27,PAAR27,PBAR127,PAAR127 |  |  |  |  |  |  |
|  |  |  |  |  | 116 | 61010PS00-012-G |  | RES,200KOhm,+/-1%,1/16W,G,SMD0402 | WALSIN TECHNOLOGY CORPORATION | WR04X2003FTL |  | G |  |  |  |  |  |  |  |
|  |  |  |  |  | 116 | 61010PS00-011-G |  | RES,200KOhm,+/-1%,1/16W,G,SMD0402 | YAGEO CORPORATION COMPONENT | RC0402FR-07200KL |  | G |  |  |  |  |  |  |  |
|  |  |  |  |  | 116 | 61010PS00-044-G |  | RES,200KOhm,+/-1%,1/16W,G,SMD0402 | TA-I TECHNOLOGY CO., LTD | RM04FTN2003 |  | G |  |  |  |  |  |  |  |
| Multi | N |  | Y(5) | 117 | 117 | 61100YD00-017-G |  | RES,9.53KOhm,+/-0.1%,1/16W,G,SMD0402 | KOA SPEER ELECTRONICS, INC. | RN731ETTP9531B25 | 2 | G | PBAR26,PAAR26 |  |  |  |  |  |  |
|  |  |  |  |  | 117 | 61100YD00-024-G |  | RES,9.53KOhm,+/-0.1%,1/16W,G,SMD0402 | PANASONIC INDUSTRIAL CO.,LTD. | ERA2AEB9531X |  | G |  |  |  |  |  |  |  |
| Multi | N | ND | Y(4) | 118 | 118 | 61010L300-017-G | - | RES,1KOhm,+/-1%,1/16W,G,SMD0402 | KOA SPEER ELECTRONICS, INC. | RK73H1ETTP1001F | 34 | G | PHAR9,PALR16,PBLR18,PBNR21,PANR21,PBMR40,PBFR40,PBER40,PBAR40,PAMR40,PAFR40,PAER40,PAAR40,R678,R679,R865,R866,R1016,R1022,R1155,R1169,R1181,R1193,R1205,R1217,R1258,R1329,R1333,R1334,R1335,R1444,R1498,R1500,R1824 |  |  |  |  |  |  |
|  |  |  |  |  | 118 | 61010L300-012-G |  | RES,1KOhm,+/-1%,1/16W,G,SMD0402 | WALSIN TECHNOLOGY CORPORATION | WR04X1001FTL |  | G |  |  |  |  |  |  |  |
|  |  |  |  |  | 118 | 61010L300-011-G |  | RES,1KOhm,+/-1%,1/16W,G,SMD0402 | YAGEO CORPORATION COMPONENT | RC0402FR-071KL |  | G |  |  |  |  |  |  |  |
|  |  |  |  |  | 118 | 61010L300-044-G |  | RES,1KOhm,+/-1%,1/16W,G,SMD0402 | TA-I TECHNOLOGY CO., LTD | RM04FTN1001 |  | G |  |  |  |  |  |  |  |
|  |  |  |  |  | 118 | 61010L300-024-G |  | RES,1KOhm,+/-1%,1/16W,G,SMD0402 | PANASONIC INDUSTRIAL CO.,LTD. | ERJ2RKF1001X |  | G |  |  |  |  |  |  |  |
|  |  |  |  |  | 118 | 61010L300-029-G |  | RES,1KOhm,+/-1%,1/16W,G,SMD0402 | VISHAY ENTER TECHNO LOGY.INC | CRCW04021K00FKED |  | G |  |  |  |  |  |  |  |
| Multi | N | Other | Y(5) | 119 | 119 | 611008W00-017-G |  | RES,73.2KOhm,+/-0.1%,1/16W,G,SMD0402 | KOA SPEER ELECTRONICS, INC. | RN731ETTP7322B25 | 8 | G | PBMR41,PBFR41,PBER41,PBAR41,PAMR41,PAFR41,PAER41,PAAR41 |  |  |  |  |  |  |
|  |  |  |  |  | 119 | 611008W00-011-G |  | RES,73.2KOhm,+/-0.1%,1/16W,G,SMD0402 | YAGEO CORPORATION COMPONENT | RT0402BRD0773K2L |  | G |  |  |  |  |  |  |  |
|  |  |  |  |  | 119 | 611008W00-012-G |  | RES,73.2KOhm,+/-0.1%,1/16W,G,SMD0402 | WALSIN TECHNOLOGY CORPORATION | WF04U7322BTL |  | G |  |  |  |  |  |  |  |
| Multi | N | other | Y(4) | 120 | 120 | 610103Y00-017-G |  | RES,10 Ohm,+/-1%,1/10W,G,SMD0603 | KOA SPEER ELECTRONICS, INC. | RK73H1JTTD10R0F | 16 | G | PHAR8,PHAR14,PHAR15,PBMR45,PBAR45,PAMR45,PAER45,PAAR45,PBMR99,PAMR99,PBER101,PAFR101,PAER101,PBFR102,PBAR105,PAAR105 |  |  |  |  |  |  |
|  |  |  |  |  | 120 | 610103Y00-012-G |  | RES,10 Ohm,+/-1%,1/10W,G,SMD0603 | WALSIN TECHNOLOGY CORPORATION | WR06X10R0FTL |  | G |  |  |  |  |  |  |  |
|  |  |  |  |  | 120 | 610103Y00-011-G |  | RES,10 Ohm,+/-1%,1/10W,G,SMD0603 | YAGEO CORPORATION COMPONENT | RC0603FR-0710RL |  | G |  |  |  |  |  |  |  |
|  |  |  |  |  | 120 | 610103Y00-044-G |  | RES,10 Ohm,+/-1%,1/10W,G,SMD0603 | TA-I TECHNOLOGY CO., LTD | RM06FTN10R0 |  | G |  |  |  |  |  |  |  |
|  |  |  |  |  | 120 | 610103Y00-024-G |  | RES,10 Ohm,+/-1%,1/10W,G,SMD0603 | PANASONIC INDUSTRIAL CO.,LTD. | ERJ3EKF10R0V |  | G |  |  |  |  |  |  |  |
| Multi |  |  | Y(4) | 121 | 121 | 61010LD00-017-G |  | RES,6.8KOhm,+/-1%,1/16W,G,SMD0402 | KOA SPEER ELECTRONICS, INC. | RK73H1ETTP6801F | 2 | G | PBAR47,PAAR47 |  |  |  |  |  |  |
|  |  |  |  |  | 121 | 61010LD00-012-G |  | RES,6.8KOhm,+/-1%,1/16W,G,SMD0402 | WALSIN TECHNOLOGY CORPORATION | WR04X6801FTL |  | G |  |  |  |  |  |  |  |
|  |  |  |  |  | 121 | 61010LD00-011-G |  | RES,6.8KOhm,+/-1%,1/16W,G,SMD0402 | YAGEO CORPORATION COMPONENT | RC0402FR-076K8L |  | G |  |  |  |  |  |  |  |
|  |  |  |  |  | 121 | 61010LD00-044-G |  | RES,6.8KOhm,+/-1%,1/16W,G,SMD0402 | TA-I TECHNOLOGY CO., LTD | RM04FTN6801 |  | G |  |  |  |  |  |  |  |
|  |  |  |  |  | 121 | 61010LD00-024-G |  | RES,6.8KOhm,+/-1%,1/16W,G,SMD0402 | PANASONIC INDUSTRIAL CO.,LTD. | ERJ2RKF6801X |  | G |  |  |  |  |  |  |  |
| Multi | ND |  | Y(4) | 122 | 122 | 61011MC02-017-G |  | Res,374 Ohm,+/-1%,1/16W,G,SMD0402 | KOA SPEER ELECTRONICS, INC. | RK73H1ETTP3740F | 8 | G | PBMR54,PBFR54,PBER54,PBAR54,PAMR54,PAFR54,PAER54,PAAR54 |  |  |  |  |  |  |
|  |  |  |  |  | 122 | 61011MC00-011-G |  | RES,374 Ohm,+/-1%,1/16W,G,SMD0402 | YAGEO CORPORATION COMPONENT | RC0402FR-07374RL |  | G |  |  |  |  |  |  |  |
|  |  |  |  |  | 122 | 61011MC00-024-G |  | RES,thick film,374Ohm,+/-1%,1/16W,SMD0402,G | PANASONIC INDUSTRIAL CO.,LTD. | ERJ2RKF3740X |  | G |  |  |  |  |  |  |  |
|  |  |  |  |  | 122 | 61011MC00-029-G |  | RES,thick film,374Ohm,+/-1%,1/16W,SMD0402,G | VISHAY ENTER TECHNO LOGY.INC | CRCW0402374RFKED |  | G |  |  |  |  |  |  |  |
| Multi | N | ND | Y(5) | 123 | 123 | 611003D00-017-G |  | RES,1KOhm,+/-0.1%,1/16W,G,SMD0402 | KOA SPEER ELECTRONICS, INC. | RN731ETTP1001B25 | 8 | G | PBMR55,PBFR55,PBER55,PBAR55,PAMR55,PAFR55,PAER55,PAAR55 |  |  |  |  |  |  |
|  |  |  |  |  | 123 | 611003D02-011-G |  | RES,1KOhm,+/-0.1%,1/16W,G,SMD0402 | YAGEO CORPORATION COMPONENT | RT0402BRD071KL |  | G |  |  |  |  |  |  |  |
|  |  |  |  |  | 123 | 611003D00-044-G |  | RES,1KOhm,+/-0.1%,1/16W,G,SMD0402 | TA-I TECHNOLOGY CO., LTD | RB04BTS1001 |  | G |  |  |  |  |  |  |  |
|  |  |  |  |  | 123 | 611003D03-012-G |  | RES,1KOhm,+/-0.1%,1/16W,G,SMD0402 | WALSIN TECHNOLOGY CORPORATION | WF04U1001BTL |  | G |  |  |  |  |  |  |  |
| Multi | N |  | Y(5) | 124 | 124 | 61100QV00-017-G |  | RES,49.9 Ohm,+/-0.5%,1/16W,G,SMD0402 | KOA SPEER ELECTRONICS, INC. | RN731ETTP49R9D50 | 8 | G | PBAR57,PAAR57,R932,R980,R981,R982,R983,R984 |  |  |  |  |  |  |
|  |  |  |  |  | 124 | 61100QV00-011-G |  | RES,49.9 Ohm,+/-0.5%,1/16W,G,SMD0402 | YAGEO CORPORATION COMPONENT | RT0402DRE0749R9L |  | G |  |  |  |  |  |  |  |
|  |  |  |  |  | 124 | 61100QV00-044-G |  | RES,49.9 Ohm,+/-0.5%,1/16W,G,SMD0402 | TA-I TECHNOLOGY CO., LTD | RB04DTS49R9 |  | G |  |  |  |  |  |  |  |
|  |  |  |  |  | 124 | 61100QV00-012-G |  | RES,49.9 Ohm,+/-0.5%,1/16W,G,SMD0402 | WALSIN TECHNOLOGY CORPORATION | WF04T49R9DTL |  | G |  |  |  |  |  |  |  |
| Multi | N |  | Y(5) | 125 | 125 | 61100QG00-017-G |  | RES,649 Ohm,+/-0.1%,1/16W,G,SMD0402 | KOA SPEER ELECTRONICS, INC. | RN731ETTP6490B25 | 2 | G | PBAR61,PAAR61 |  |  |  |  |  |  |
|  |  |  |  |  | 125 | 61100QG00-024-G |  | RES,649 Ohm,+/-0.1%,1/16W,G,SMD0402 | PANASONIC INDUSTRIAL CO.,LTD. | ERA2AEB6490X |  | G |  |  |  |  |  |  |  |
|  |  |  |  |  | 125 | 61100QG00-029-G |  | RES,649 Ohm,+/-0.1%,1/16W,G,SMD0402 | VISHAY ENTER TECHNO LOGY.INC | TNPW0402649RBEED |  | G |  |  |  |  |  |  |  |
| Multi | N | ND | Y(4) | 126 | 126 | 610113800-017-G | - | RES,10 Ohm,+/-1%,1/16W,G,SMD0402 | KOA SPEER ELECTRONICS, INC. | RK73H1ETTP10R0F | 27 | G | PBFR45,PBER45,PAFR45,PBER61,PAFR61,PAER61,PBFR62,PBER62,PAFR62,PAER62,PBMR63,PBFR63,PBAR63,PAMR63,PAAR63,PBMR64,PBAR64,PAMR64,PAAR64,PBFR518,PBER518,PAFR518,PBFR519,PBER519,PAFR519,PAER519,PAER520 |  |  |  |  |  |  |
|  |  |  |  |  | 126 | 610113800-012-G |  | RES,10 Ohm,+/-1%,1/16W,G,SMD0402 | WALSIN TECHNOLOGY CORPORATION | WR04X10R0FTL |  | G |  |  |  |  |  |  |  |
|  |  |  |  |  | 126 | 610113800-011-G |  | RES,10 Ohm,+/-1%,1/16W,G,SMD0402 | YAGEO CORPORATION COMPONENT | RC0402FR-0710RL |  | G |  |  |  |  |  |  |  |
|  |  |  |  |  | 126 | 610113800-044-G |  | RES,10 Ohm,+/-1%,1/16W,G,SMD0402 | TA-I TECHNOLOGY CO., LTD | RM04FTN10R0 |  | G |  |  |  |  |  |  |  |
| Multi | ND |  | ND | 127 | 127 | 610606G00-017-G |  | RES,20mOhm,+/-1%,5W,G,SMD2512 | KOA SPEER ELECTRONICS, INC. | TLRH3APTTE20L0F | 2 | G | PBAR65,PAAR65 |  |  |  |  |  |  |
|  |  |  |  |  | 127 | 610605400-125-G |  | RES,20mOhm,+/-1%,1W,G,SMD2512 | INTERNATIONAL RESISTIVE COMPANY, INC. | LRMAP2512-R02FT4 |  | G |  |  |  |  |  |  |  |
| Multi | N | ND | ND | 128 | 128 | 61010R900-017-G | - | RES,27.4KOhm,+/-1%,1/10W,G,SMD0603 | KOA SPEER ELECTRONICS, INC. | RK73H1JTTD2742F | 8 | G | PAMR66,PAAR66,PBAR67,PBMR69,PBMR76,PAMR76,PBAR79,PAAR79 |  |  |  |  |  |  |
|  |  |  |  |  | 128 | 61010R900-012-G |  | RES,27.4KOhm,+/-1%,1/10W,G,SMD0603 | WALSIN TECHNOLOGY CORPORATION | WR06X2742FTL |  | G |  |  |  |  |  |  |  |
|  |  |  |  |  | 128 | 61010R900-011-G |  | RES,27.4KOhm,+/-1%,1/10W,G,SMD0603 | YAGEO CORPORATION COMPONENT | RC0603FR-0727K4L |  | G |  |  |  |  |  |  |  |
| Multi | N | ND | Y(4) | 129 | 129 | 61010G500-017-G | - | RES,10KOhm,+/-1%,1/16W,G,SMD0402 | KOA SPEER ELECTRONICS, INC. | RK73H1ETTP1002F | 103 | G | PSUR2,PANR5,PSTR6,PSLR6,PSFR6,PSER6,PSDR6,PQPR6,PFRR6,PEER6,PEDR6,PBNR6,PUAR7,PSIR7,PSAR7,PRAR7,PQAR7,PPAR7,PIAR7,PFAR7,PETR7,PERR7,PEAR7,PHAR22,PHAR39,PAAR67,PBAR68,PBER74,PAFR74,PAER74,PBMR75,PBFR75,PAMR75,PBAR78,PAAR78,PBMR300,PBFR300,PBER300,PBAR300,PAMR300,PAFR300,PAER300,PAAR300,PBMR305,PBFR305,PBER305,PBAR305,PAMR305,PAFR305,PAER305,PAAR305,PBMR306,PBFR306,PBER306,PBAR306,PAMR306,PAFR306,PAER306,PAAR306,PBMR307,PBFR307,PBER307,PBAR307,PAMR307,PAFR307,PAER307,PAAR307,R330,R351,R353,R357,R359,R480,R481,R482,R483,R719,R864,R910,R912,R913,R914,R915,R916,R917,R1075,R1076,R1077,R1078,R1118,R1136,R1137,R1441,R1482,R1490,R1534,R1535,R1536,R1537,R1538,R1539,R1540,PSRR3001 |  |  |  |  |  |  |
|  |  |  |  |  | 129 | 61010G500-012-G |  | RES,10KOhm,+/-1%,1/16W,G,SMD0402 | WALSIN TECHNOLOGY CORPORATION | WR04X1002FTL |  | G |  |  |  |  |  |  |  |
|  |  |  |  |  | 129 | 61010G500-011-G |  | RES,10KOhm,+/-1%,1/16W,G,SMD0402 | YAGEO CORPORATION COMPONENT | RC0402FR-0710KL |  | G |  |  |  |  |  |  |  |
|  |  |  |  |  | 129 | 61010G500-044-G |  | RES,10KOhm,+/-1%,1/16W,G,SMD0402 | TA-I TECHNOLOGY CO., LTD | RM04FTN1002 |  | G |  |  |  |  |  |  |  |
|  |  |  |  |  | 129 | 61010G500-029-G |  | RES,10KOhm,+/-1%,1/16W,G,SMD0402 | VISHAY ENTER TECHNO LOGY.INC | CRCW040210K0FKED |  | G |  |  |  |  |  |  |  |
|  |  |  |  |  | 129 | 61010G500-024-G |  | RES,10KOhm,+/-1%,1/16W,G,SMD0402 | PANASONIC INDUSTRIAL CO.,LTD. | ERJ2RKF1002X |  | G |  |  |  |  |  |  |  |
| Multi | ND | ND | ND | 130 | 130 | 610108U00-017-G | - | RES,10KOhm,+/-1%,1/10W,G,SMD0603 | KOA SPEER ELECTRONICS, INC. | RK73H1JTTD1002F | 10 | G | PAAR70,PBAR71,PBER72,PAFR72,PAER72,PBFR73,PBMR74,PAMR74,PBAR77,PAAR77 |  |  |  |  |  |  |
|  |  |  |  |  | 130 | 610108U00-012-G |  | RES,10KOhm,+/-1%,1/10W,G,SMD0603 | WALSIN TECHNOLOGY CORPORATION | WR06X1002FTL |  | G |  |  |  |  |  |  |  |
|  |  |  |  |  | 130 | 610108U00-011-G |  | RES,10KOhm,+/-1%,1/10W,G,SMD0603 | YAGEO CORPORATION COMPONENT | RC0603FR-0710KL |  | G |  |  |  |  |  |  |  |
|  |  |  |  |  | 130 | 610108U00-044-G |  | RES,10KOhm,+/-1%,1/10W,G,SMD0603 | TA-I TECHNOLOGY CO., LTD | RM06FTN1002 |  | G |  |  |  |  |  |  |  |
|  |  |  |  |  | 130 | 610108U00-024-G |  | RES,10KOhm,+/-1%,1/10W,G,SMD0603 | PANASONIC INDUSTRIAL CO.,LTD. | ERJ3EKF1002V |  | G |  |  |  |  |  |  |  |
| Multi | ND | ND | ND | 131 | 131 | 610100C00-017-G | - | RES,15kOhm,+/-1%,1/10W,G,SMD0603 | KOA SPEER ELECTRONICS, INC. | RK73H1JTTD1502F | 2 | G | PBAR80,PAAR80 |  |  |  |  |  |  |
|  |  |  |  |  | 131 | 610100C00-011-G |  | RES,15KOhm,+/-1%,1/10W,G,SMD0603 | YAGEO CORPORATION COMPONENT | RC0603FR-0715KL |  | G |  |  |  |  |  |  |  |
|  |  |  |  |  | 131 | 610100C00-012-G |  | RES,15KOhm,+/-1%,1/10W,G,SMD0603 | WALSIN TECHNOLOGY CORPORATION | WR06X1502FTL |  | G |  |  |  |  |  |  |  |
|  |  |  |  |  | 131 | 610100C00-044-G |  | RES,15KOhm,+/-1%,1/10W,G,SMD0603 | TA-I TECHNOLOGY CO., LTD | RM06FTN1502 |  | G |  |  |  |  |  |  |  |
| Multi | ND | ND | Y(4) | 132 | 132 | 61011A500-017-G | - | RES,1.74KOhm,+/-1%,1/16W,G,SMD0402 | KOA SPEER ELECTRONICS, INC. | RK73H1ETTP1741F | 8 | G | PBMR81,PAMR81,PBER83,PAFR83,PAER83,PBFR84,PBAR84,PAAR84 |  |  |  |  |  |  |
|  |  |  |  |  | 132 | 61011A500-012-G |  | RES,1.74KOhm,+/-1%,1/16W,G,SMD0402 | WALSIN TECHNOLOGY CORPORATION | WR04X1741FTL |  | G |  |  |  |  |  |  |  |
|  |  |  |  |  | 132 | 61011A500-011-G |  | RES,1.74KOhm,+/-1%,1/16W,G,SMD0402 | YAGEO CORPORATION COMPONENT | RC0402FR-071K74L |  | G |  |  |  |  |  |  |  |
|  |  |  |  |  | 132 | 61011A500-044-G |  | RES,1.74KOhm,+/-1%,1/16W,G,SMD0402 | TA-I TECHNOLOGY CO., LTD | RM04FTN1741 |  | G |  |  |  |  |  |  |  |
|  |  |  |  |  | 132 | 61011A500-024-G |  | RES,1.74KOhm,+/-1%,1/16W,G,SMD0402 | PANASONIC INDUSTRIAL CO.,LTD. | ERJ2RKF1741X |  | G |  |  |  |  |  |  |  |
| Multi | N |  | Y(5) | 133 | 133 | 61100LR00-017-G |  | RES,100 Ohm,+/-1%,1/16W,G,SMD0402 | KOA SPEER ELECTRONICS, INC. | RN731ETTP1000F50 | 31 | G | PSPR6,PIPR6,PFPR6,PEPR6,PALR14,PALR15,PALR19,PBLR20,PALR20,PBLR21,PBLR23,PBLR24,PBER68,PBMR82,PAMR82,PBAR85,PAAR85,PAFR87,PAER87,PBFR88,PBMR91,PAMR91,PBAR93,PAAR93,PBMR94,PAMR94,PBAR96,PAAR96,R1484,R1745,R1785 |  |  |  |  |  |  |
|  |  |  |  |  | 133 | 61100LR01-011-G |  | RES,100 Ohm,+/-1%,1/16W,G,SMD0402 | YAGEO CORPORATION COMPONENT | RT0402FRE07100RL |  | G |  |  |  |  |  |  |  |
|  |  |  |  |  | 133 | 61100LR00-044-G |  | RES,100 Ohm,+/-1%,1/16W,G,SMD0402 | TA-I TECHNOLOGY CO., LTD | RB04FTS1000 |  | G |  |  |  |  |  |  |  |
|  |  |  |  |  | 133 | 61100LR00-012-G |  | RES,100 Ohm,+/-1%,1/16W,G,SMD0402 | WALSIN TECHNOLOGY CORPORATION | WF04T1000FTL |  | G |  |  |  |  |  |  |  |
| Multi | N | other | Y(4) | 134 | 134 | 61010CB00-017-G |  | RES,49.9 Ohm,+/-1%,1/10W,G,SMD0603 | KOA SPEER ELECTRONICS, INC. | RK73H1JTTD49R9F | 8 | G | PBER85,PAFR85,PBMR86,PBFR86,PBAR86,PAMR86,PAAR86,PAER672 |  |  |  |  |  |  |
|  |  |  |  |  | 134 | 61010CB00-012-G |  | RES,49.9 Ohm,+/-1%,1/10W,G,SMD0603 | WALSIN TECHNOLOGY CORPORATION | WR06X49R9FTL |  | G |  |  |  |  |  |  |  |
|  |  |  |  |  | 134 | 61010CB00-011-G |  | RES,49.9 Ohm,+/-1%,1/10W,G,SMD0603 | YAGEO CORPORATION COMPONENT | RC0603FR-0749R9L |  | G |  |  |  |  |  |  |  |
|  |  |  |  |  | 134 | 61010CB00-044-G |  | RES,49.9 Ohm,+/-1%,1/10W,G,SMD0603 | TA-I TECHNOLOGY CO., LTD | RM06FTN49R9 |  | G |  |  |  |  |  |  |  |
|  |  |  |  |  | 134 | 61010CB00-024-G |  | RES,49.9 Ohm,+/-1%,1/10W,G,SMD0603 | PANASONIC INDUSTRIAL CO.,LTD. | ERJ3EKF49R9V |  | G |  |  |  |  |  |  |  |
| Multi | N | Other | Y(4) | 135 | 135 | 610130Y00-017-G |  | RES,1 Ohm,+/-1%,1/3W,G,SMD1206 | KOA SPEER ELECTRONICS, INC. | SR732BTTD1R00F | 11 | G | PHAR4,PBMR90,PAMR90,PBER92,PBAR92,PAFR92,PAER92,PAAR92,PBFR93,PBAR102,PAAR102 |  |  |  |  |  |  |
|  |  |  |  |  | 135 | 610122P00-012-G |  | RES,1 Ohm,+/-1%,1/2W,G,SMD1206 | WALSIN TECHNOLOGY CORPORATION | WF12P1R00FTL |  | G |  |  |  |  |  |  |  |
|  |  |  |  |  | 135 | 610122P00-011-G |  | RES,1 Ohm,+/-1%,1/2W,G,SMD1206 | YAGEO CORPORATION COMPONENT | RC1206FR-7W1RL |  | G |  |  |  |  |  |  |  |
|  |  |  |  |  | 135 | 610122P00-044-G |  | RES,1 Ohm,+/-1%,1/2W,G,SMD1206 | TA-I TECHNOLOGY CO., LTD | RMH12FT1R00 |  | G |  |  |  |  |  |  |  |
| Multi | ND | ND | Y(5) | 136 | 136 | 611003200-017-G |  | RES,10KOhm,+/-0.1%,1/16W,G,SMD0402 | KOA SPEER ELECTRONICS, INC. | RN731ETTP1002B25 | 34 | G | PBMR26,PAMR26,PBMR97,PAMR97,PBMR98,PAMR98,PBER99,PAFR99,PAER99,PBMR100,PBFR100,PBER100,PAMR100,PAFR100,PAER100,PBFR101,PBMR102,PBER102,PAMR102,PAFR102,PAER102,PBFR103,PBAR103,PAAR103,PBER104,PBAR104,PAFR104,PAER104,PAAR104,PBFR105,PBAR106,PAAR106,PBAR108,PAAR108 |  |  |  |  |  |  |
|  |  |  |  |  | 136 | 611003200-044-G |  | RES,10KOhm,+/-0.1%,1/16W,G,SMD0402 | TA-I TECHNOLOGY CO., LTD | RB04BTP1002 |  | G |  |  |  |  |  |  |  |
|  |  |  |  |  | 136 | 611003200-011-G |  | RES,10KOhm,+/-0.1%,1/16W,G,SMD0402 | YAGEO CORPORATION COMPONENT | RT0402BRE0710KL |  | G |  |  |  |  |  |  |  |
|  |  |  |  |  | 136 | 611003200-012-G |  | RES,10KOhm,+/-0.1%,1/16W,G,SMD0402 | WALSIN TECHNOLOGY CORPORATION | WF04U1002BTL |  | G |  |  |  |  |  |  |  |
| Multi | N | ND | ND | 137 | 137 | 61100M100-017-G | - | RES,4.75KOhm,+/-1%,1/16W,G,SMD0402 | KOA SPEER ELECTRONICS, INC. | RN731ETTP4751F50 | 2 | G | PBAR109,PAAR109 |  |  |  |  |  |  |
|  |  |  |  |  | 137 | 61100M100-011-G |  | RES,4.75KOhm,+/-1%,1/16W,G,SMD0402 | YAGEO CORPORATION COMPONENT | RT0402FRE074K75L |  | G |  |  |  |  |  |  |  |
|  |  |  |  |  | 137 | 61100M100-012-G |  | RES,4.75KOhm,+/-1%,1/16W,G,SMD0402 | WALSIN TECHNOLOGY CORPORATION | WF04T4751FTL |  | G |  |  |  |  |  |  |  |
|  |  |  |  |  | 137 | 61100M100-044-G |  | RES,4.75KOhm,+/-1%,1/16W,G,SMD0402 | TA-I TECHNOLOGY CO., LTD | RB04FTS4751 |  | G |  |  |  |  |  |  |  |
| Multi | N | Other | Y(4) | 138 | 138 | 61011B300-017-G | - | RES,1MOhm,+/-1%,1/16W,G,SMD0402 | KOA SPEER ELECTRONICS, INC. | RK73H1ETTP1004F | 9 | G | PBMR107,PAMR107,PBER109,PAFR109,PAER109,PBFR110,PBAR113,PAAR113,R1844 |  |  |  |  |  |  |
|  |  |  |  |  | 138 | 61011B300-012-G |  | RES,1MOhm,+/-1%,1/16W,G,SMD0402 | WALSIN TECHNOLOGY CORPORATION | WR04X1004FTL |  | G |  |  |  |  |  |  |  |
|  |  |  |  |  | 138 | 61011B300-011-G |  | RES,1MOhm,+/-1%,1/16W,G,SMD0402 | YAGEO CORPORATION COMPONENT | RC0402FR-071ML |  | G |  |  |  |  |  |  |  |
|  |  |  |  |  | 138 | 61011B300-044-G |  | RES,1MOhm,+/-1%,1/16W,G,SMD0402 | TA-I TECHNOLOGY CO., LTD | RM04FTN1004 |  | G |  |  |  |  |  |  |  |
| Multi | ND |  | Y(4) | 139 | 139 | 61011GU00-017-G |  | RES,274 Ohm,+/-1%,1/16W,G,SMD0402 | KOA SPEER ELECTRONICS, INC. | RK73H1ETTP2740F | 8 | G | PBMR109,PAMR109,PBER111,PAFR111,PAER111,PBFR112,PBAR115,PAAR115 |  |  |  |  |  |  |
|  |  |  |  |  | 139 | 61011GU00-012-G |  | RES,274 Ohm,+/-1%,1/16W,G,SMD0402 | WALSIN TECHNOLOGY CORPORATION | WR04X2740FTL |  | G |  |  |  |  |  |  |  |
|  |  |  |  |  | 139 | 61011GU00-011-G |  | RES,274 Ohm,+/-1%,1/16W,G,SMD0402 | YAGEO CORPORATION COMPONENT | RC0402FR-07274RL |  | G |  |  |  |  |  |  |  |
|  |  |  |  |  | 139 | 61011GU00-044-G |  | RES,274 Ohm,+/-1%,1/16W,G,SMD0402 | TA-I TECHNOLOGY CO., LTD | RM04FTN2740 |  | G |  |  |  |  |  |  |  |
| Multi | N |  | Y(5) | 140 | 140 | 61100RU00-017-G |  | RES,59 Ohm,+/-1%,1/16W,G,SMD0402 | KOA SPEER ELECTRONICS, INC. | RN731ETTP59R0F25 | 8 | G | PBMR113,PAMR113,PBER115,PAFR115,PAER115,PBFR116,PBAR119,PAAR119 |  |  |  |  |  |  |
|  |  |  |  |  | 140 | 61100RU00-011-G |  | RES,59 Ohm,+/-1%,1/16W,G,SMD0402 | YAGEO CORPORATION COMPONENT | RT0402FRE0759RL |  | G |  |  |  |  |  |  |  |
| Multi | ND | ND | Y(4) | 141 | 141 | 610114P00-017-G | - | RES,715 Ohm,+/-1%,1/16W,G,SMD0402 | KOA SPEER ELECTRONICS, INC. | RK73H1ETTP7150F | 8 | G | PBMR117,PAMR117,PBER119,PAFR119,PAER119,PBFR120,PBAR123,PAAR123 |  |  |  |  |  |  |
|  |  |  |  |  | 141 | 610114P00-012-G |  | RES,715 Ohm,+/-1%,1/16W,G,SMD0402 | WALSIN TECHNOLOGY CORPORATION | WR04X7150FTL |  | G |  |  |  |  |  |  |  |
|  |  |  |  |  | 141 | 610114P00-011-G |  | RES,715 Ohm,+/-1%,1/16W,G,SMD0402 | YAGEO CORPORATION COMPONENT | RC0402FR-07715RL |  | G |  |  |  |  |  |  |  |
| Multi | ND | ND | Y(4) | 142 | 142 | 61011L200-017-G |  | RES,3.65KOhm,+/-1%,1/16W,G,SMD0402 | KOA SPEER ELECTRONICS, INC. | RK73H1ETTP3651F | 9 | G | PHAR79,PBMR118,PAMR118,PBER120,PAFR120,PAER120,PBFR121,PBAR124,PAAR124 |  |  |  |  |  |  |
|  |  |  |  |  | 142 | 61011L200-012-G |  | RES,3.65KOhm,+/-1%,1/16W,G,SMD0402 | WALSIN TECHNOLOGY CORPORATION | WR04X3651FTL |  | G |  |  |  |  |  |  |  |
|  |  |  |  |  | 142 | 61011L200-011-G |  | RES,3.65KOhm,+/-1%,1/16W,G,SMD0402 | YAGEO CORPORATION COMPONENT | RC0402FR-073K65L |  | G |  |  |  |  |  |  |  |
|  |  |  |  |  | 142 | 61011L200-044-G |  | RES,3.65KOhm,+/-1%,1/16W,G,SMD0402 | TA-I TECHNOLOGY CO., LTD | RM04FTN3651 |  | G |  |  |  |  |  |  |  |
| Multi | ND | ND | Y(4) | 143 | 143 | 61011BH00-017-G |  | RES,22.1 Ohm,+/-1%,1/16W,G,SMD0402 | KOA SPEER ELECTRONICS, INC. | RK73H1ETTP22R1F | 4 | G | PBMR304,PBAR304,PAMR304,PAAR304 |  |  |  |  |  |  |
|  |  |  |  |  | 143 | 61011BH00-012-G |  | RES,22.1 Ohm,+/-1%,1/16W,G,SMD0402 | WALSIN TECHNOLOGY CORPORATION | WR04X22R1FTL |  | G |  |  |  |  |  |  |  |
|  |  |  |  |  | 143 | 61011BH00-011-G |  | RES,22.1 Ohm,+/-1%,1/16W,G,SMD0402 | YAGEO CORPORATION COMPONENT | RC0402FR-0722R1L |  | G |  |  |  |  |  |  |  |
|  |  |  |  |  | 143 | 61011BH00-044-G |  | RES,22.1 Ohm,+/-1%,1/16W,G,SMD0402 | TA-I TECHNOLOGY CO., LTD | RM04FTN22R1 |  | G |  |  |  |  |  |  |  |
| Multi | ND |  | Y(4) | 144 | 144 | 61012JH00-017-G |  | RES,470 Ohm,+/-5%,1/8W,G,SMD0805 | KOA SPEER ELECTRONICS, INC. | RK73B2ATTD471J | 37 | G | PUAR13,PSAR13,PRAR13,PQAR13,PPAR13,PIAR13,PFAR13,PEAR13,PSIR14,PETR14,PERR14,PALR18,PSTR20,PSLR20,PSFR20,PSER20,PSDR20,PQPR20,PFRR20,PEER20,PEDR20,PBLR22,PBMR452,PBNR502,PBFR502,PBER502,PANR502,PAMR502,PAFR502,PAAR502,PBAR504,PAER514,PSPR3000,PIPR3000,PFPR3000,PEPR3000,PSRR3009 |  |  |  |  |  |  |
|  |  |  |  |  | 144 | 61012JH00-012-G |  | RES,470 Ohm,+/-5%,1/8W,G,SMD0805 | WALSIN TECHNOLOGY CORPORATION | WR08X471JTL |  | G |  |  |  |  |  |  |  |
|  |  |  |  |  | 144 | 61012JH00-011-G |  | RES,470 Ohm,+/-5%,1/8W,G,SMD0805 | YAGEO CORPORATION COMPONENT | RC0805JR-07470RL |  | G |  |  |  |  |  |  |  |
|  |  |  |  |  | 144 | 61012JH00-044-G |  | RES,470 Ohm,+/-5%,1/8W,G,SMD0805 | TA-I TECHNOLOGY CO., LTD | RM10JTN471 |  | G |  |  |  |  |  |  |  |
| Multi | N | ND | Y(4) | 145 | 145 | 610114J00-017-G | - | RES,2KOhm,+/-1%,1/16W,G,SMD0402 | KOA SPEER ELECTRONICS, INC. | RK73H1ETTP2001F | 11 | G | R347,R348,R350,PBFR510,PBER510,PAFR510,PAER510,PBMR600,PBAR600,PAMR600,PAAR600 |  |  |  |  |  |  |
|  |  |  |  |  | 145 | 610114J00-012-G |  | RES,2KOhm,+/-1%,1/16W,G,SMD0402 | WALSIN TECHNOLOGY CORPORATION | WR04X2001FTL |  | G |  |  |  |  |  |  |  |
|  |  |  |  |  | 145 | 610114J00-011-G |  | RES,2KOhm,+/-1%,1/16W,G,SMD0402 | YAGEO CORPORATION COMPONENT | RC0402FR-072KL |  | G |  |  |  |  |  |  |  |
|  |  |  |  |  | 145 | 610114J00-044-G |  | RES,2KOhm,+/-1%,1/16W,G,SMD0402 | TA-I TECHNOLOGY CO., LTD | RM04FTN2001 |  | G |  |  |  |  |  |  |  |
|  |  |  |  |  | 145 | 610114J00-024-G |  | RES,2KOhm,+/-1%,1/16W,G,SMD0402 | PANASONIC INDUSTRIAL CO.,LTD. | ERJ2RKF2001X |  | G |  |  |  |  |  |  |  |
|  |  |  |  |  | 145 | 610114J00-029-G |  | RES,2KOhm,+/-1%,1/16W,G,SMD0402 | VISHAY ENTER TECHNO LOGY.INC | CRCW04022K00FKED |  | G |  |  |  |  |  |  |  |
| Multi | ND | ND | Y(4) | 146 | 146 | 61010L100-017-G | - | RES,100KOhm,+/-1%,1/16W,G,SMD0402 | KOA SPEER ELECTRONICS, INC. | RK73H1ETTP1003F | 17 | G | PBFR511,PBER511,PAFR511,PAER511,PBMR603,PBAR603,PAMR603,PAAR603,PBMR604,PBAR604,PAMR604,PAAR604,PAFR634,PBFR659,PBER659,PAER684,R1559 |  |  |  |  |  |  |
|  |  |  |  |  | 146 | 61010L100-012-G |  | RES,100KOhm,+/-1%,1/16W,G,SMD0402 | WALSIN TECHNOLOGY CORPORATION | WR04X1003FTL |  | G |  |  |  |  |  |  |  |
|  |  |  |  |  | 146 | 61010L100-011-G |  | RES,100KOhm,+/-1%,1/16W,G,SMD0402 | YAGEO CORPORATION COMPONENT | RC0402FR-07100KL |  | G |  |  |  |  |  |  |  |
|  |  |  |  |  | 146 | 61010L100-044-G |  | RES,100KOhm,+/-1%,1/16W,G,SMD0402 | TA-I TECHNOLOGY CO., LTD | RM04FTN1003 |  | G |  |  |  |  |  |  |  |
|  |  |  |  |  | 146 | 61010L106-029-G |  | RES,100KOhm,+/-1%,1/16W,G,SMD0402 | VISHAY ENTER TECHNO LOGY.INC | CRCW0402100KFKEDC |  | G |  |  |  |  |  |  |  |
|  |  |  |  |  | 146 | 61010L100-024-G |  | RES,100KOhm,+/-1%,1/16W,G,SMD0402 | PANASONIC INDUSTRIAL CO.,LTD. | ERJ2RKF1003X |  | G |  |  |  |  |  |  |  |
| Multi | ND |  | Y(4) | 147 | 147 | 61013A200-017-G |  | RES,6.8 Ohm,+/-1%,1/4W,G,SMD1206 | KOA SPEER ELECTRONICS, INC. | RK73H2BTTD6R80F | 4 | G | PBMR605,PBAR605,PAMR605,PAAR605 |  |  |  |  |  |  |
|  |  |  |  |  | 147 | 61013A200-011-G |  | RES,6.8 Ohm,+/-1%,1/4W,G,SMD1206 | YAGEO CORPORATION COMPONENT | RC1206FR-076R8L |  | G |  |  |  |  |  |  |  |
|  |  |  |  |  | 147 | 61013A200-044-G |  | RES,6.8 Ohm,+/-1%,1/4W,G,SMD1206 | TA-I TECHNOLOGY CO., LTD | RM12FTN6R8 |  | G |  |  |  |  |  |  |  |
|  |  |  |  |  | 147 | 61013A200-029-G |  | RES,6.8 Ohm,+/-1%,1/4W,G,SMD1206 | VISHAY ENTER TECHNO LOGY.INC | CRCW12066R80FKEA |  | G |  |  |  |  |  |  |  |
| Multi | ND | ND | Y(4) | 148 | 148 | 61011MG00-017-G |  | RES,42.2KOhm,+/-1%,1/16W,G,SMD0402 | KOA SPEER ELECTRONICS, INC. | RK73H1ETTP4222F | 8 | G | PBFR512,PBER512,PAFR512,PAER512,PBMR606,PBAR606,PAMR606,PAAR606 |  |  |  |  |  |  |
|  |  |  |  |  | 148 | 61011MG00-012-G |  | RES,42.2KOhm,+/-1%,1/16W,G,SMD0402 | WALSIN TECHNOLOGY CORPORATION | WR04X4222FTL |  | G |  |  |  |  |  |  |  |
|  |  |  |  |  | 148 | 61011MG00-011-G |  | RES,42.2KOhm,+/-1%,1/16W,G,SMD0402 | YAGEO CORPORATION COMPONENT | RC0402FR-0742K2L |  | G |  |  |  |  |  |  |  |
|  |  |  |  |  | 148 | 61011MG00-044-G |  | RES,42.2KOhm,+/-1%,1/16W,G,SMD0402 | TA-I TECHNOLOGY CO., LTD | RM04FTN4222 |  | G |  |  |  |  |  |  |  |
| Single | ND | ND | Y(1) | 149 | 149 | 32040FG00-183-G |  | IC,Current Sensor,INA193AIDBVR,G,SOT23-5,SMD | TEXAS INSTRUMENTS | INA193AIDBVR | 8 | G | PBMU2,PBFU2,PBEU2,PBAU2,PAMU2,PAFU2,PAEU2,PAAU2 |  |  |  |  |  |  |
| Single | N |  | N | 150 | 150 | 32014E200-53N-G |  | IC,Regulator,PI3753-00-LGIZ,ADJ,10.3A,G,LGA-108,SMD | Vicor Corporation | PI3753-00-LGIZ | 2 | G | PBAU3,PAAU3 |  |  |  |  |  |  |
| Single | N |  | N | 151 | 151 | 880302200-53N-G |  | Converter,input 0V~60V,185W,G,VTM48MP012T130AA0 | Vicor Corporation | VTM48MP012T130AA0 | 4 | G | PBAU4,PAAU4,PBAU6,PAAU6 |  |  |  |  |  |  |
| Single | N |  | Y(3) | 152 | 152 | 32031MS00-183-G |  | IC,Operation Amplifier,OPA2365AIDR,G,SOIC-8,SMD | TEXAS INSTRUMENTS | OPA2365AIDR | 8 | G | PBMU5,PBFU5,PBEU5,PAMU5,PAFU5,PAEU5,PBAU7,PAAU7 |  |  |  |  |  |  |
| Multi | ND | ND | Y(3) | 153 | 153 | 620108600-015-G | - | CAP,180pF,+/-5%,NPO(C0G),50V,G,SMD0402 | MURATA ELEC. NORTH AMERICA | GRM1555C1H181J | 4 | G | PBFC4,PBEC4,PAFC4,PAEC4 |  |  |  |  |  |  |
|  |  |  |  |  | 153 | 620108600-026-G |  | CAP,180pF,+/-5%,NPO(C0G),50V,G,SMD0402 | SAMSUNG SEMICONDUCTOR | CL05C181JB5NNNC |  | G |  |  |  |  |  |  |  |
|  |  |  |  |  | 153 | 620108600-023-G |  | CAP,180pF,+/-5%,NPO(C0G),50V,G,SMD0402 | TAIYO ELECTRIC IND.CO.LTD | UMK105CG181JV-F |  | G |  |  |  |  |  |  |  |
|  |  |  |  |  | 153 | 620108600-011-G |  | CAP,180pF,+/-5%,NPO(C0G),50V,G,SMD0402 | YAGEO CORPORATION COMPONENT | CC0402JRNPO9BN181 |  | G |  |  |  |  |  |  |  |
| Multi | N | ND | Y(3) | 154 | 154 | 62010WW01-015-G | - | CAP,1.8nF,+/-10%,X7R,50V,G,SMD0402 | MURATA ELEC. NORTH AMERICA | GRM155R71H182KA01D | 4 | G | PBFC59,PBEC59,PAFC59,PAEC59 |  |  |  |  |  |  |
|  |  |  |  |  | 154 | 62010WW00-026-G |  | CAP,1.8nF,+/-10%,X7R,50V,G,SMD0402 | SAMSUNG SEMICONDUCTOR | CL05B182KB5NNNC |  | G |  |  |  |  |  |  |  |
| Multi | Y | 2 | Y(3) | 155 | 155 | 62011FQ00-015-G | - | CAP,5.6nF,+/-10%,X7R,50V,G,SMD0402 | MURATA ELEC. NORTH AMERICA | GRM155R71H562K | 6 | G | PBFC60,PBEC60,PAFC60,PAEC60,PBMC61,PAMC61 |  |  |  |  |  |  |
|  |  |  |  |  | 155 | 62011FQ00-026-G |  | CAP,5.6nF,+/-10%,X7R,50V,G,SMD0402 | SAMSUNG SEMICONDUCTOR | CL05B562KB5NNNC |  | G |  |  |  |  |  |  |  |
|  |  |  |  |  | 155 | 62011FQ00-023-G |  | CAP,5.6nF,+/-10%,X7R,50V,G,SMD0402 | TAIYO ELECTRIC IND.CO.LTD | UMK105B7562KV-F |  | G |  |  |  |  |  |  |  |
| Multi | ND | ND | Y(1) | 156 | 156 | 730100L00-086-G |  | Fuse,Very fast acting,125V,5A,G,SMD | LITTELFUSE FAR EAST PTE LTD | 0451005.MRL | 6 | G | PBFFS1,PBEFS1,PAMFS1,PAFFS1,PAEFS1,PAMFS2 |  |  |  |  |  |  |
|  |  |  |  |  | 156 | 730107B01-088-G |  | Fuse,Fast acting,125V,5A,SMD,G | COOPER BUSSMANN, INC. | CB61F5A-TR2 |  | G |  |  |  |  |  |  |  |
| Multi | N |  | N | 157 | 157 | 63035NF00-57M-G |  | IND,1.5uH@100KHz,+/-10%,12A,6mOhm,SHLD,G,SMD | Eaton Corporation | HCV1206-1R5-R | 6 | G | PBFL1,PBEL1,PAFL1,PAEL1,PBML2,PAML2 |  |  |  |  |  |  |
|  |  |  |  |  | 157 | 630362H00-065-G |  | IND,1.5uH@100KHz,+/-10%,12A,6.6mOhm,SHLD,G,SMD | DELTA ELECTRONICS INDUSTRIAL CO.,LTD | HMS1360-1R5 |  | G |  |  |  |  |  |  |  |
| Multi | ND |  | Y(4) | 158 | 158 | 610117V00-017-G |  | RES,680 Ohm,+/-1%,1/16W,G,SMD0402 | KOA SPEER ELECTRONICS, INC. | RK73H1ETTP6800F | 4 | G | PBER4,PAER4,R972,R1090 |  |  |  |  |  |  |
|  |  |  |  |  | 158 | 610117V00-012-G |  | RES,680 Ohm,+/-1%,1/16W,G,SMD0402 | WALSIN TECHNOLOGY CORPORATION | WR04X6800FTL |  | G |  |  |  |  |  |  |  |
|  |  |  |  |  | 158 | 610117V00-011-G |  | RES,680 Ohm,+/-1%,1/16W,G,SMD0402 | YAGEO CORPORATION COMPONENT | RC0402FR-07680RL |  | G |  |  |  |  |  |  |  |
|  |  |  |  |  | 158 | 610117V00-044-G |  | RES,680 Ohm,+/-1%,1/16W,G,SMD0402 | TA-I TECHNOLOGY CO., LTD | RM04FTN6800 |  | G |  |  |  |  |  |  |  |
| Multi | ND |  | Y(5) | 159 | 159 | 61100RN00-017-G |  | RES,15.4KOhm,+/-0.1%,1/16W,G,SMD0402 | KOA SPEER ELECTRONICS, INC. | RN731ETTP1542B25 | 4 | G | PBFR26,PBER26,PAFR26,PAER26 |  |  |  |  |  |  |
|  |  |  |  |  | 159 | 61100RN00-011-G |  | RES,15.4KOhm,+/-0.1%,1/16W,G,SMD0402 | YAGEO CORPORATION COMPONENT | RT0402BRD0715K4L |  | G |  |  |  |  |  |  |  |
|  |  |  |  |  | 159 | 61100RN00-044-G |  | RES,15.4KOhm,+/-0.1%,1/16W,G,SMD0402 | TA-I TECHNOLOGY CO., LTD | RB04BTP1542 |  | G |  |  |  |  |  |  |  |
|  |  |  |  |  | 159 | 61100RN00-012-G |  | RES,15.4KOhm,+/-0.1%,1/16W,G,SMD0402 | WALSIN TECHNOLOGY CORPORATION | WF04U1542BTL |  | G |  |  |  |  |  |  |  |
| Single | N |  | Y(4) | 160 | 160 | 61100YT00-017-G |  | RES,487 Ohm,+/-0.1%,1/16W,G,SMD0402 | KOA SPEER ELECTRONICS, INC. | RN731ETTP4870B25 | 4 | G | PBFR34,PBER34,PAFR34,PAER34 |  |  |  |  |  |  |
| Multi | N | ND | Y(4) | 161 | 161 | 61011DR00-017-G |  | RES,2.2KOhm,+/-1%,1/16W,G,SMD0402 | KOA SPEER ELECTRONICS, INC. | RK73H1ETTP2201F | 9 | G | PBFR47,PBER47,PAFR47,PAER47,R781,R782,R1018,R1024,R1730 |  |  |  |  |  |  |
|  |  |  |  |  | 161 | 61011DR00-012-G |  | RES,2.2KOhm,+/-1%,1/16W,G,SMD0402 | WALSIN TECHNOLOGY CORPORATION | WR04X2201FTL |  | G |  |  |  |  |  |  |  |
|  |  |  |  |  | 161 | 61011DR00-011-G |  | RES,2.2KOhm,+/-1%,1/16W,G,SMD0402 | YAGEO CORPORATION COMPONENT | RC0402FR-072K2L |  | G |  |  |  |  |  |  |  |
|  |  |  |  |  | 161 | 61011DR00-044-G |  | RES,2.2KOhm,+/-1%,1/16W,G,SMD0402 | TA-I TECHNOLOGY CO., LTD | RM04FTN2201 |  | G |  |  |  |  |  |  |  |
|  |  |  |  |  | 161 | 61011DR00-029-G |  | RES,2.2KOhm,+/-1%,1/16W,G,SMD0402 | VISHAY ENTER TECHNO LOGY.INC | CRCW04022K20FKED |  | G |  |  |  |  |  |  |  |
| Multi | ND |  | Y(4) | 162 | 162 | 610127L00-017-G |  | RES,215 Ohm,+/-1%,1/16W,G,SMD0402 | KOA SPEER ELECTRONICS, INC. | RK73H1ETTP2150F | 4 | G | PBFR57,PBER57,PAFR57,PAER57 |  |  |  |  |  |  |
|  |  |  |  |  | 162 | 610127L00-011-G |  | RES,215 Ohm,+/-1%,1/16W,G,SMD0402 | YAGEO CORPORATION COMPONENT | RC0402FR-07215RL |  | G |  |  |  |  |  |  |  |
|  |  |  |  |  | 162 | 610127L00-012-G |  | RES,215 Ohm,+/-1%,1/16W,G,SMD0402 | WALSIN TECHNOLOGY CORPORATION | WR04X2150FTL |  | G |  |  |  |  |  |  |  |
|  |  |  |  |  | 162 | 610127L00-044-G |  | RES,215 Ohm,+/-1%,1/16W,G,SMD0402 | TA-I TECHNOLOGY CO., LTD | RM04FTN2150 |  | G |  |  |  |  |  |  |  |
| Multi | ND | ND | Y(4) | 163 | 163 | 610108V00-017-G | - | RES,2KOhm,+/-1%,1/10W,G,SMD0603 | KOA SPEER ELECTRONICS, INC. | RK73H1JTTD2001F | 6 | G | PBER58,PAFR58,PAER58,PBFR59,PBMR61,PAMR61 |  |  |  |  |  |  |
|  |  |  |  |  | 163 | 610108V00-012-G |  | RES,2KOhm,+/-1%,1/10W,G,SMD0603 | WALSIN TECHNOLOGY CORPORATION | WR06X2001FTL |  | G |  |  |  |  |  |  |  |
|  |  |  |  |  | 163 | 610108V00-011-G |  | RES,2KOhm,+/-1%,1/10W,G,SMD0603 | YAGEO CORPORATION COMPONENT | RC0603FR-072KL |  | G |  |  |  |  |  |  |  |
|  |  |  |  |  | 163 | 610108V00-044-G |  | RES,2KOhm,+/-1%,1/10W,G,SMD0603 | TA-I TECHNOLOGY CO., LTD | RM06FTN2001 |  | G |  |  |  |  |  |  |  |
|  |  |  |  |  | 163 | 610108V00-024-G |  | RES,2KOhm,+/-1%,1/10W,G,SMD0603 | PANASONIC INDUSTRIAL CO.,LTD. | ERJ3EKF2001V |  | G |  |  |  |  |  |  |  |
| Multi | ND |  | N | 164 | 164 | 610606H00-017-G |  | RES,50mOhm,+/-1%,1.5W,G,SMD2512 | KOA | SLW1TTE50L0F | 4 | G | PBER65,PAFR65,PAER65,PBFR66 |  |  |  |  |  |  |
|  |  |  |  |  | 164 | 610606E00-125-G |  | RES,50mOhm,+/-1%,1W,G,SMD2512 | INTERNATIONAL RESISTIVE COMPANY, INC. | LRMAP2512-R05FT4 |  | G |  |  |  |  |  |  |  |
| Multi | ND | ND | Y(4) | 165 | 165 | 61010RW00-017-G | - | RES,23.2KOhm,+/-1%,1/10W,G,SMD0603 | KOA SPEER ELECTRONICS, INC. | RK73H1JTTD2322F | 8 | G | PBER66,PAFR66,PAER66,PBFR67,PBER67,PAFR67,PAER67,PBFR68 |  |  |  |  |  |  |
|  |  |  |  |  | 165 | 61010RW00-012-G |  | RES,23.2KOhm,+/-1%,1/10W,G,SMD0603 | WALSIN TECHNOLOGY CORPORATION | WR06X2322FTL |  | G |  |  |  |  |  |  |  |
|  |  |  |  |  | 165 | 61010RW00-011-G |  | RES,23.2KOhm,+/-1%,1/10W,G,SMD0603 | YAGEO CORPORATION COMPONENT | RC0603FR-0723K2L |  | G |  |  |  |  |  |  |  |
|  |  |  |  |  | 165 | 61010RW00-044-G |  | RES,23.2KOhm,+/-1%,1/10W,G,SMD0603 | TA-I TECHNOLOGY CO., LTD | RM06FTN2322 |  | G |  |  |  |  |  |  |  |
|  |  |  |  |  | 165 | 61010RW00-029-G |  | RES,23.2KOhm,+/-1%,1/10W,G,SMD0603 | VISHAY ENTER TECHNO LOGY.INC | CRCW060323K2FKEA |  | G |  |  |  |  |  |  |  |
|  |  |  |  |  | 165 | 61010RW00-024-G |  | RES,23.2KOhm,+/-1%,1/10W,G,SMD0603 | PANASONIC INDUSTRIAL CO.,LTD. | ERJ3EKF2322V |  | G |  |  |  |  |  |  |  |
| Multi | N | Other | Y(4) | 166 | 166 | 610107K00-017-G | - | RES,24.9KOhm,+/-1%,1/10W,G,SMD0603 | KOA SPEER ELECTRONICS, INC. | RK73H1JTTD2492F | 4 | G | PBER84,PAFR84,PAER84,PBFR85 |  |  |  |  |  |  |
|  |  |  |  |  | 166 | 610107K00-011-G |  | RES,24.9KOhm,+/-1%,1/10W,G,SMD0603 | YAGEO CORPORATION COMPONENT | RC0603FR-0724K9L |  | G |  |  |  |  |  |  |  |
|  |  |  |  |  | 166 | 610107K00-012-G |  | RES,24.9KOhm,+/-1%,1/10W,G,SMD0603 | WALSIN TECHNOLOGY CORPORATION | WR06X2492FTL |  | G |  |  |  |  |  |  |  |
| Multi | ND |  | Y(4) | 167 | 167 | 61015NJ00-017-G |  | RES,6.04 Ohm,+/-1%,1/4W,G,SMD1206 | KOA SPEER ELECTRONICS, INC. | RK73H2BTTD6R04F | 4 | G | PBFR513,PBER513,PAFR513,PAER513 |  |  |  |  |  |  |
|  |  |  |  |  | 167 | 61015NJ00-012-G |  | RES,6.04 Ohm,+/-1%,1/4W,G,SMD1206 | WALSIN TECHNOLOGY CORPORATION | WR12W6R04FTL |  | G |  |  |  |  |  |  |  |
|  |  |  |  |  | 167 | 61015NJ00-011-G |  | RES,6.04 Ohm,+/-1%,1/4W,G,SMD1206 | YAGEO CORPORATION COMPONENT | RC1206FR-076R04L |  | G |  |  |  |  |  |  |  |
| Single | N |  | N | 168 | 168 | 32014CE00-53N-G |  | IC,Regulator,PI3755-02-LGIZ,ADJ,4A,G,LGA-71,SMD | Vicor Corporation | PI3755-02-LGIZ | 6 | G | PBMU3,PBFU3,PBEU3,PAMU3,PAFU3,PAEU3 |  |  |  |  |  |  |
| Single | N | ND | N | 169 | 169 | 880302600-53N-G | - | Converter,input 0V~52V,120W,G,VTM48RP015C076AG0 | Vicor Corporation | VTM48RP015C076AG0 | 4 | G | PBFU4,PBEU4,PAFU4,PAEU4 |  |  |  |  |  |  |
| Multi | N | Other | Y(4) | 170 | 170 | 610117U00-017-G | - | RES,820 Ohm,+/-1%,1/16W,G,SMD0402 | KOA SPEER ELECTRONICS, INC. | RK73H1ETTP8200F | 2 | G | PBFR3,PAFR3 |  |  |  |  |  |  |
|  |  |  |  |  | 170 | 610117U00-012-G |  | RES,820 Ohm,+/-1%,1/16W,G,SMD0402 | WALSIN TECHNOLOGY CORPORATION | WR04X8200FTL |  | G |  |  |  |  |  |  |  |
|  |  |  |  |  | 170 | 610117U00-011-G |  | RES,820 Ohm,+/-1%,1/16W,G,SMD0402 | YAGEO CORPORATION COMPONENT | RC0402FR-07820RL |  | G |  |  |  |  |  |  |  |
|  |  |  |  |  | 170 | 610117U00-044-G |  | RES,820 Ohm,+/-1%,1/16W,G,SMD0402 | TA-I TECHNOLOGY CO., LTD | RM04FTN8200 |  | G |  |  |  |  |  |  |  |
| Multi | Y | 2 | Y(3) | 171 | 171 | 620109700-015-G |  | CAP,3.3nF,+/-10%,X7R,50V,G,SMD0402 | MURATA ELEC. NORTH AMERICA | GRM155R71H332K | 21 | G | PIPC10,PFPC10,PEPC10,PBNC11,PANC11,PBNC13,PANC13,PUAC18,PSAC18,PRAC18,PQAC18,PPAC18,PIAC18,PFAC18,PEAC18,PBNC25,PANC25,PALC35,PALC40,PBLC56,PBLC60 |  |  |  |  |  |  |
|  |  |  |  |  | 171 | 620109700-012-G |  | CAP,3.3nF,+/-10%,X7R,50V,G,SMD0402 | WALSIN TECHNOLOGY CORPORATION | 0402B332K500CT |  | G |  |  |  |  |  |  |  |
|  |  |  |  |  | 171 | 620109700-026-G |  | CAP,3.3nF,+/-10%,X7R,50V,G,SMD0402 | SAMSUNG SEMICONDUCTOR | CL05B332KB5NNNC |  | G |  |  |  |  |  |  |  |
| Multi | Y |  | Y(1) | 172 | 172 | 620131D00-015-G |  | CAP,1uF,+/-10%,X6S,16V,G,SMD0402 | MURATA ELEC. NORTH AMERICA | GRM155C81C105KE11J | 6 | G | PHAC1,PANC1,PBNC2,PHAC7,PALC37,PBLC62 |  |  |  |  |  |  |
|  |  |  |  |  | 172 | 620131D00-023-G |  | CAP,1uF,+/-10%,X6S,16V,G,SMD0402 | TAIYO ELECTRIC IND.CO.LTD | EMK105C6105KV-F |  | G |  |  |  |  |  |  |  |
| Multi | N |  | Y(3) | 173 | 173 | 62012GG00-015-G |  | CAP,10uF,+/-10%,X7S,25V,G,SMD0805 | MURATA ELEC. NORTH AMERICA | GRM21BC71E106K | 68 | G | PSTC2,PSLC2,PSFC2,PSEC2,PSDC2,PQPC2,PFRC2,PEEC2,PEDC2,PANC2,PSTC3,PSLC3,PSFC3,PSEC3,PSDC3,PQPC3,PFRC3,PEEC3,PEDC3,PBNC3,PANC3,PBNC4,PANC4,PBNC5,PANC5,PSPC6,PIPC6,PFPC6,PEPC6,PBNC6,PSPC7,PIPC7,PFPC7,PEPC7,PSPC8,PIPC8,PFPC8,PEPC8,PSPC9,PIPC9,PFPC9,PEPC9,PSTC17,PSTC18,PALC38,PALC39,PBLC54,PBLC55,PSPC3004,PIPC3004,PFPC3004,PEPC3004,PSPC3005,PIPC3005,PFPC3005,PEPC3005,PSPC3006,PIPC3006,PFPC3006,PEPC3006,PSPC3007,PIPC3007,PFPC3007,PEPC3007,PSPC3009,PIPC3009,PFPC3009,PEPC3009 |  |  |  |  |  |  |
|  |  |  |  |  | 173 | 62012GG00-012-G |  | CAP,10uF,+/-10%,X7S,25V,G,SMD0805 | WALSIN TECHNOLOGY CORPORATION | 0805A106K250CT |  | G |  |  |  |  |  |  |  |
| Multi | N |  | N | 174 | 174 | 72010RE00-015-G |  | FB,26 Ohm@100MHz,+/-25%,6A,7mOhm,G,SMD0603 | MURATA ELEC. NORTH AMERICA | BLM18KG260TN1D | 22 | G | PSTL1,PSLL1,PSFL1,PSEL1,PSDL1,PQPL1,PFRL1,PEEL1,PEDL1,PBLL1,PALL1,PUAL2,PSIL2,PSAL2,PRAL2,PQAL2,PPAL2,PIAL2,PFAL2,PERL2,PEAL2,PQPL3 |  |  |  |  |  |  |
|  |  |  |  |  | 174 | 72010SJ00-059-G |  | FB,26 Ohm@100MHz,+/-25%,6A,10mOhm,G,SMD0603 | TAI-TECH ADVANCED ELECTRONICS CO., LTD. | HCB1608KF-260T60 |  | G |  |  |  |  |  |  |  |
| Multi | ND |  | N | 175 | 175 | 630351600-034-G |  | IND,470nH@100KHz,+/-20%,30A,1.68mOhm,SHLD,G,SMD | CYNTEC CO. LTD | PCMB104T-R47MS | 2 | G | PALL2,PBLL4 |  |  |  |  |  |  |
|  |  |  |  |  | 175 | 63035YA00-051-G |  | Coil Ind,Shielded(SHLD),470nH@100KHz,+/-20%,28A,1.5mOhm,SMD,11.5*10.3*4.0,,,G | PULSE ELECTRONICS (SINGAPORE) | PA4342.471NLT |  | G |  |  |  |  |  |  |  |
|  |  |  |  |  | 175 | 63035Y900-129-G |  | IND,470nH@100KHz,+/-20%,30A,1.68mOhm,SHLD,G,SMD | MAG.LAYERS, SCIENTIFIC-TECHNICS (KUNSHAN) CO., LTD. | SPS-10DZ-R47M-X2 |  | G |  |  |  |  |  |  |  |
| Single | N |  | N | 176 | 176 | 320244200-230-G |  | IC,PWM Controller,ISL99227FRZ-T,G,QFN-32,SMD | INTERSIL CORPORATION | ISL99227FRZ-T | 2 | G | PALU1,PBLU3 |  |  |  |  |  |  |
| Multi | Y | 2 | Y(3) | 177 | 177 | 62010BH00-015-G | - | CAP,220pF,+/-5%,NPO(C0G),50V,G,SMD0402 | MURATA ELEC. NORTH AMERICA | GRM1555C1H221J | 2 | G | PBMC4,PAMC4 |  |  |  |  |  |  |
|  |  |  |  |  | 177 | 62010BH02-012-G |  | CAP,220pF,+/-5%,NPO(C0G),50V,G,SMD0402 | WALSIN TECHNOLOGY CORPORATION | 0402N221J500CT |  | G |  |  |  |  |  |  |  |
|  |  |  |  |  | 177 | 62010BH00-011-G |  | CAP,220pF,+/-5%,NPO(C0G),50V,G,SMD0402 | YAGEO CORPORATION COMPONENT | CC0402JRNPO9BN221 |  | G |  |  |  |  |  |  |  |
|  |  |  |  |  | 177 | 62010BH00-026-G |  | CAP,220pF,+/-5%,NPO(C0G),50V,G,SMD0402 | SAMSUNG SEMICONDUCTOR | CL05C221JB5NNNC |  | G |  |  |  |  |  |  |  |
|  |  |  |  |  | 177 | 62010BH03-023-G |  | CAP,220pF,+/-5%,NPO(C0G),50V,G,SMD0402 | TAIYO ELECTRIC IND.CO.LTD | UMK105CG221JV-F |  | G |  |  |  |  |  |  |  |
| Multi | ND | ND | Y(4) | 178 | 178 | 61011QD00-017-G | - | RES,330 Ohm,+/-1%,1/16W,G,SMD0402 | KOA SPEER ELECTRONICS, INC. | RK73H1ETTP3300F | 2 | G | PBMR3,PAMR12 |  |  |  |  |  |  |
|  |  |  |  |  | 178 | 61011QD00-012-G |  | RES,330 Ohm,+/-1%,1/16W,G,SMD0402 | WALSIN TECHNOLOGY CORPORATION | WR04X3300FTL |  | G |  |  |  |  |  |  |  |
|  |  |  |  |  | 178 | 61011QD00-011-G |  | RES,330 Ohm,+/-1%,1/16W,G,SMD0402 | YAGEO CORPORATION COMPONENT | RC0402FR-07330RL |  | G |  |  |  |  |  |  |  |
|  |  |  |  |  | 178 | 61011QD00-044-G |  | RES,330 Ohm,+/-1%,1/16W,G,SMD0402 | TA-I TECHNOLOGY CO., LTD | RM04FTN3300 |  | G |  |  |  |  |  |  |  |
| Single | ND |  | Y(5) | 179 | 179 | 61100YW00-017-G |  | RES,316 Ohm,+/-0.1%,1/16W,G,SMD0402 | KOA SPEER ELECTRONICS, INC. | RN731ETTP3160B25 | 2 | G | PBMR34,PAMR34 |  |  |  |  |  |  |
| Multi | ND |  | Y(4) | 180 | 180 | 61011HT00-017-G |  | RES,1.8KOhm,+/-1%,1/16W,G,SMD0402 | KOA SPEER ELECTRONICS, INC. | RK73H1ETTP1801F | 2 | G | PBMR47,PAMR47 |  |  |  |  |  |  |
|  |  |  |  |  | 180 | 61011HT00-012-G |  | RES,1.8KOhm,+/-1%,1/16W,G,SMD0402 | WALSIN TECHNOLOGY CORPORATION | WR04X1801FTL |  | G |  |  |  |  |  |  |  |
|  |  |  |  |  | 180 | 61011HT00-011-G |  | RES,1.8KOhm,+/-1%,1/16W,G,SMD0402 | YAGEO CORPORATION COMPONENT | RC0402FR-071K8L |  | G |  |  |  |  |  |  |  |
|  |  |  |  |  | 180 | 61011HT00-044-G |  | RES,1.8KOhm,+/-1%,1/16W,G,SMD0402 | TA-I TECHNOLOGY CO., LTD | RM04FTN1801 |  | G |  |  |  |  |  |  |  |
|  |  |  |  |  | 180 | 61011HT00-029-G |  | RES,1.8KOhm,+/-1%,1/16W,G,SMD0402 | VISHAY ENTER TECHNO LOGY.INC | CRCW04021K80FKED |  | G |  |  |  |  |  |  |  |
|  |  |  |  |  | 180 | ERA2RKF1801X |  | RES,1.8KOhm,+/-1%,1/16W,G,SMD0402 | PANASONIC INDUSTRIAL CO.,LTD. | ERA2RKF1801X |  | G |  |  |  |  |  |  |  |
| Multi | ND | ND | Y(4) | 181 | 181 | 610119U00-017-G | - | RES,133 Ohm,+/-1%,1/16W,G,SMD0402 | KOA SPEER ELECTRONICS, INC. | RK73H1ETTP1330F | 2 | G | PBMR57,PAMR57 |  |  |  |  |  |  |
|  |  |  |  |  | 181 | 610119U00-011-G |  | RES,133 Ohm,+/-1%,1/16W,G,SMD0402 | YAGEO CORPORATION COMPONENT | RC0402FR-07133RL |  | G |  |  |  |  |  |  |  |
|  |  |  |  |  | 181 | 610119U00-012-G |  | RES,133 Ohm,+/-1%,1/16W,G,SMD0402 | WALSIN TECHNOLOGY CORPORATION | WR04X1330FTL |  | G |  |  |  |  |  |  |  |
|  |  |  |  |  | 181 | 610119U00-044-G |  | RES,133 Ohm,+/-1%,1/16W,G,SMD0402 | TA-I TECHNOLOGY CO., LTD | RM04FTN1330 |  | G |  |  |  |  |  |  |  |
| Multi | ND |  | N | 182 | 182 | 610606J00-017-G |  | RES,75mOhm,+/-1%,1.5W,G,SMD2512 | KOA | SLW1TTE75L0F | 2 | G | PBMR65,PAMR65 |  |  |  |  |  |  |
|  |  |  |  |  | 182 | 610606D00-125-G |  | RES,75mOhm,+/-1%,1W,G,SMD2512 | INTERNATIONAL RESISTIVE COMPANY, INC. | LRMAP2512-R075FT4 |  | G |  |  |  |  |  |  |  |
| Multi | ND | ND | Y(4) | 183 | 183 | 61010A700-017-G | - | RES,30.9KOhm,+/-1%,1/10W,G,SMD0603 | KOA SPEER ELECTRONICS, INC. | RK73H1JTTD3092F | 2 | G | PBMR77,PAMR77 |  |  |  |  |  |  |
|  |  |  |  |  | 183 | 61010A700-011-G |  | RES,30.9KOhm,+/-1%,1/10W,G,SMD0603 | YAGEO CORPORATION COMPONENT | RC0603FR-0730K9L |  | G |  |  |  |  |  |  |  |
|  |  |  |  |  | 183 | 61010A700-012-G |  | RES,30.9KOhm,+/-1%,1/10W,G,SMD0603 | WALSIN TECHNOLOGY CORPORATION | WR06X3092FTL |  | G |  |  |  |  |  |  |  |
| Multi | N | ND | Y(4) | 184 | 184 | 61011FU00-017-G |  | RES,115KOhm,+/-1%,1/16W,G,SMD0402 | KOA SPEER ELECTRONICS, INC. | RK73H1ETTP1153F | 2 | G | PBMR121,PAMR121 |  |  |  |  |  |  |
|  |  |  |  |  | 184 | 61011FU00-011-G |  | RES,115KOhm,+/-1%,1/16W,G,SMD0402 | YAGEO CORPORATION COMPONENT | RC0402FR-07115KL |  | G |  |  |  |  |  |  |  |
|  |  |  |  |  | 184 | 61011FU00-012-G |  | RES,115KOhm,+/-1%,1/16W,G,SMD0402 | WALSIN TECHNOLOGY CORPORATION | WR04X1153FTL |  | G |  |  |  |  |  |  |  |
|  |  |  |  |  | 184 | 61011FU00-044-G |  | RES,115KOhm,+/-1%,1/16W,G,SMD0402 | TA-I TECHNOLOGY CO., LTD | RM04FTN1153 |  | G |  |  |  |  |  |  |  |
| Single | N |  | N | 185 | 185 | 880302800-53N-G |  | Converter,input 0V~60V,131W,G,VTM48MP010C105AG0 | Vicor Corporation | VTM48MP010C105AG0 | 2 | G | PBMU4,PAMU4 |  |  |  |  |  |  |
| Multi | ND | ND | N | 186 | 186 | 62010HR00-015-G | - | CAP,100nF,+/-10%,X7R,50V,G,SMD0603 | MURATA ELEC. NORTH AMERICA | GRM188R71H104K | 13 | G | PUAC8,PSIC8,PSAC8,PRAC8,PQAC8,PPAC8,PIAC8,PFAC8,PETC8,PERC8,PEAC8,PBNC10,PANC10 |  |  |  |  |  |  |
|  |  |  |  |  | 186 | 62010HR00-026-G |  | CAP,100nF,+/-10%,X7R,50V,G,SMD0603 | SAMSUNG SEMICONDUCTOR | CL10B104KB8NNNC |  | G |  |  |  |  |  |  |  |
| Multi | ND |  | N | 187 | 187 | 630330G00-088-G |  | IND,300nH@100KHz,+/-10%,32.5A,304.5uOhm,SHLD,G,SMD | COOPER BUSSMANN, INC. | FP0906R1-R30-R | 2 | G | PBNL1,PANL1 |  |  |  |  |  |  |
|  |  |  |  |  | 187 | 630332A01-051-G |  | Coil Ind,Shielded(SHLD),300nH@100KHz,+/-10%,33A,304.5uOhm,SMD,9.2*6.2*7.8,G | PULSE ELECTRONICS (SINGAPORE) | PA3288.301HLT |  | G |  |  |  |  |  |  |  |
|  |  |  |  |  | 187 | 630330G00-129-G |  | IND,300nH@100KHz,+/-10%,32.5A,290uOhm,SHLD,G,SMD | MAG.LAYERS, SCIENTIFIC-TECHNICS (KUNSHAN) CO., LTD. | MSI-900608-R30K-E |  | G |  |  |  |  |  |  |  |
| Multi | ND |  | Y(4) | 188 | 188 | 61011JH00-017-G |  | RES,19.1KOhm,+/-1%,1/16W,G,SMD0402 | KOA SPEER ELECTRONICS, INC. | RK73H1ETTP1912F | 6 | G | PANR6,PBNR7,R355,R356,R361,R362 |  |  |  |  |  |  |
|  |  |  |  |  | 188 | 61011JH00-012-G |  | RES,19.1KOhm,+/-1%,1/16W,G,SMD0402 | WALSIN TECHNOLOGY CORPORATION | WR04X1912FTL |  | G |  |  |  |  |  |  |  |
|  |  |  |  |  | 188 | 61011JH00-011-G |  | RES,19.1KOhm,+/-1%,1/16W,G,SMD0402 | YAGEO CORPORATION COMPONENT | RC0402FR-0719K1L |  | G |  |  |  |  |  |  |  |
|  |  |  |  |  | 188 | 61011JH00-044-G |  | RES,19.1KOhm,+/-1%,1/16W,G,SMD0402 | TA-I TECHNOLOGY CO., LTD | RM04FTN1912 |  | G |  |  |  |  |  |  |  |
| Multi | ND | ND | Y(4) | 189 | 189 | 610114S00-017-G | - | RES,4.99KOhm,+/-1%,1/16W,G,SMD0402 | KOA SPEER ELECTRONICS, INC. | RK73H1ETTP4991F | 3 | G | PFRR3,PBNR5,PANR7 |  |  |  |  |  |  |
|  |  |  |  |  | 189 | 610114S00-012-G |  | RES,4.99KOhm,+/-1%,1/16W,G,SMD0402 | WALSIN TECHNOLOGY CORPORATION | WR04X4991FTL |  | G |  |  |  |  |  |  |  |
|  |  |  |  |  | 189 | 610114S00-011-G |  | RES,4.99KOhm,+/-1%,1/16W,G,SMD0402 | YAGEO CORPORATION COMPONENT | RC0402FR-074K99L |  | G |  |  |  |  |  |  |  |
|  |  |  |  |  | 189 | 610114S00-044-G |  | RES,4.99KOhm,+/-1%,1/16W,G,SMD0402 | TA-I TECHNOLOGY CO., LTD | RM04FTN4991 |  | G |  |  |  |  |  |  |  |
|  |  |  |  |  | 189 | 610114S00-024-G |  | RES,4.99KOhm,+/-1%,1/16W,G,SMD0402 | PANASONIC INDUSTRIAL CO.,LTD. | ERJ2RKF4991X |  | G |  |  |  |  |  |  |  |
| Multi | ND | ND | Y(4) | 190 | 190 | 610114B00-017-G |  | RES,2.49KOhm,+/-1%,1/16W,G,SMD0402 | KOA SPEER ELECTRONICS, INC. | RK73H1ETTP2491F | 2 | G | PBNR11,PANR11 |  |  |  |  |  |  |
|  |  |  |  |  | 190 | 610114B00-012-G |  | RES,2.49KOhm,+/-1%,1/16W,G,SMD0402 | WALSIN TECHNOLOGY CORPORATION | WR04X2491FTL |  | G |  |  |  |  |  |  |  |
|  |  |  |  |  | 190 | 610114B00-011-G |  | RES,2.49KOhm,+/-1%,1/16W,G,SMD0402 | YAGEO CORPORATION COMPONENT | RC0402FR-072K49L |  | G |  |  |  |  |  |  |  |
|  |  |  |  |  | 190 | 610114B00-024-G |  | RES,2.49KOhm,+/-1%,1/16W,G,SMD0402 | PANASONIC INDUSTRIAL CO.,LTD. | ERJ2RKF2491X |  | G |  |  |  |  |  |  |  |
|  |  |  |  |  | 190 | 610114B00-029-G |  | RES,2.49KOhm,+/-1%,1/16W,G,SMD0402 | VISHAY ENTER TECHNO LOGY.INC | CRCW04022K49FKED |  | G |  |  |  |  |  |  |  |
| Multi | N | Other | Y(4) | 191 | 191 | 61011CJ00-017-G | - | RES,365 Ohm,+/-1%,1/16W,G,SMD0402 | KOA SPEER ELECTRONICS, INC. | RK73H1ETTP3650F | 2 | G | PBNR14,PANR14 |  |  |  |  |  |  |
|  |  |  |  |  | 191 | 61011CJ00-012-G |  | RES,365 Ohm,+/-1%,1/16W,G,SMD0402 | WALSIN TECHNOLOGY CORPORATION | WR04X3650FTL |  | G |  |  |  |  |  |  |  |
|  |  |  |  |  | 191 | 61011CJ00-011-G |  | RES,365 Ohm,+/-1%,1/16W,G,SMD0402 | YAGEO CORPORATION COMPONENT | RC0402FR-07365RL |  | G |  |  |  |  |  |  |  |
|  |  |  |  |  | 191 | 61011CJ00-024-G |  | RES,365 Ohm,+/-1%,1/16W,G,SMD0402 | PANASONIC INDUSTRIAL CO.,LTD. | ERJ2RKF3650X |  | G |  |  |  |  |  |  |  |
|  |  |  |  |  | 191 | 61011CJ00-029-G |  | RES,365 Ohm,+/-1%,1/16W,G,SMD0402 | VISHAY ENTER TECHNO LOGY.INC | CRCW0402365RFKEDC |  | G |  |  |  |  |  |  |  |
| Multi | ND | ND | Y(4) | 192 | 192 | 610112G00-017-G | - | RES,20 Ohm,+/-1%,1/16W,G,SMD0402 | KOA SPEER ELECTRONICS, INC. | RK73H1ETTP20R0F | 2 | G | PBNR15,PANR15 |  |  |  |  |  |  |
|  |  |  |  |  | 192 | 610112G00-012-G |  | RES,20 Ohm,+/-1%,1/16W,G,SMD0402 | WALSIN TECHNOLOGY CORPORATION | WR04X20R0FTL |  | G |  |  |  |  |  |  |  |
|  |  |  |  |  | 192 | 610112G00-011-G |  | RES,20 Ohm,+/-1%,1/16W,G,SMD0402 | YAGEO CORPORATION COMPONENT | RC0402FR-0720RL |  | G |  |  |  |  |  |  |  |
|  |  |  |  |  | 192 | 610112G00-044-G |  | RES,20 Ohm,+/-1%,1/16W,G,SMD0402 | TA-I TECHNOLOGY CO., LTD | RM04FTN20R0 |  | G |  |  |  |  |  |  |  |
|  |  |  |  |  | 192 | 610112G00-024-G |  | RES,20 Ohm,+/-1%,1/16W,G,SMD0402 | PANASONIC INDUSTRIAL CO.,LTD. | ERJ2RKF20R0X |  | G |  |  |  |  |  |  |  |
| Multi | ND |  | Y(5) | 193 | 193 | 611005R00-017-G |  | RES,100 Ohm,+/-0.1%,1/16W,G,SMD0402 | KOA SPEER ELECTRONICS, INC. | RN731ETTP1000B25 | 5 | G | PSRR16,PBNR16,PANR16,PBNR18,PANR18 |  |  |  |  |  |  |
|  |  |  |  |  | 193 | 611005R00-011-G |  | RES,100 Ohm,+/-0.1%,1/16W,G,SMD0402 | YAGEO CORPORATION COMPONENT | RT0402BRE07100RL |  | G |  |  |  |  |  |  |  |
|  |  |  |  |  | 193 | 611005R00-044-G |  | RES,100 Ohm,+/-0.1%,1/16W,G,SMD0402 | TA-I TECHNOLOGY CO., LTD | RB04BTP1000 |  | G |  |  |  |  |  |  |  |
|  |  |  |  |  | 193 | 611005R00-012-G |  | RES,100 Ohm,+/-0.1%,1/16W,G,SMD0402 | WALSIN TECHNOLOGY CORPORATION | WF04U1000BTL |  | G |  |  |  |  |  |  |  |
| Multi | ND | ND | Y(4) | 194 | 194 | 61011B600-017-G | - | RES,5.36KOhm,+/-1%,1/16W,G,SMD0402 | KOA SPEER ELECTRONICS, INC. | RK73H1ETTP5361F | 2 | G | PBNR17,PANR17 |  |  |  |  |  |  |
|  |  |  |  |  | 194 | 61011B600-012-G |  | RES,5.36KOhm,+/-1%,1/16W,G,SMD0402 | WALSIN TECHNOLOGY CORPORATION | WR04X5361FTL |  | G |  |  |  |  |  |  |  |
|  |  |  |  |  | 194 | 61011B600-011-G |  | RES,5.36KOhm,+/-1%,1/16W,G,SMD0402 | YAGEO CORPORATION COMPONENT | RC0402FR-075K36L |  | G |  |  |  |  |  |  |  |
|  |  |  |  |  | 194 | 61011B600-044-G |  | RES,5.36KOhm,+/-1%,1/16W,G,SMD0402 | TA-I TECHNOLOGY CO., LTD | RM04FTN5361 |  | G |  |  |  |  |  |  |  |
| Multi | ND | ND | Y(4) | 195 | 195 | 61010LA00-017-G | - | RES,4.7KOhm,+/-1%,1/16W,G,SMD0402 | KOA SPEER ELECTRONICS, INC. | RK73H1ETTP4701F | 152 | G | PSRR20,PBNR23,PANR23,PHAR28,PHAR29,PHAR30,R668,R669,R683,R762,R763,R764,R765,R766,R767,R769,R770,R772,R773,R774,R775,R776,R777,R778,R779,R780,R783,R784,R786,R787,R788,R791,R795,R800,R801,R804,R805,R806,R807,R808,R809,R811,R814,R817,R820,R822,R823,R825,R827,R828,R830,R893,R894,R901,R902,R922,R942,R943,R944,R945,R949,R950,R955,R956,R957,R958,R959,R1017,R1023,R1129,R1135,R1138,R1148,R1149,R1150,R1151,R1152,R1156,R1159,R1162,R1164,R1165,R1172,R1174,R1175,R1176,R1184,R1185,R1186,R1190,R1195,R1197,R1198,R1199,R1210,R1211,R1212,R1213,R1218,R1219,R1220,R1221,R1222,R1223,R1224,R1256,R1257,R1295,R1296,R1461,R1463,R1464,R1465,R1467,R1469,R1470,R1471,R1474,R1475,R1476,R1477,R1495,R1504,R1507,R1508,R1509,R1511,R1512,R1515,R1520,R1521,R1550,R1551,R1558,R1589,R1590,R1592,R1593,R1603,R1604,R1605,R1606,R1779,R1780,R1781,R1782,R1786,R1789,R1801,R1820,R1821,R1834 |  |  |  |  |  |  |
|  |  |  |  |  | 195 | 61010LA00-012-G |  | RES,4.7KOhm,+/-1%,1/16W,G,SMD0402 | WALSIN TECHNOLOGY CORPORATION | WR04X4701FTL |  | G |  |  |  |  |  |  |  |
|  |  |  |  |  | 195 | 61010LA00-011-G |  | RES,4.7KOhm,+/-1%,1/16W,G,SMD0402 | YAGEO CORPORATION COMPONENT | RC0402FR-074K7L |  | G |  |  |  |  |  |  |  |
|  |  |  |  |  | 195 | 61010LA00-044-G |  | RES,4.7KOhm,+/-1%,1/16W,G,SMD0402 | TA-I TECHNOLOGY CO., LTD | RM04FTN4701 |  | G |  |  |  |  |  |  |  |
| Multi | N | ND | Y(4) | 196 | 196 | 61011CS00-017-G | - | RES,750KOhm,+/-1%,1/16W,G,SMD0402 | KOA SPEER ELECTRONICS, INC. | RK73H1ETTP7503F | 2 | G | PBNR24,PANR24 |  |  |  |  |  |  |
|  |  |  |  |  | 196 | 61011CS00-012-G |  | RES,750KOhm,+/-1%,1/16W,G,SMD0402 | WALSIN TECHNOLOGY CORPORATION | WR04X7503FTL |  | G |  |  |  |  |  |  |  |
|  |  |  |  |  | 196 | 61011CS00-011-G |  | RES,750KOhm,+/-1%,1/16W,G,SMD0402 | YAGEO CORPORATION COMPONENT | RC0402FR-07750KL |  | G |  |  |  |  |  |  |  |
| Multi | ND | ND | Y(4) | 197 | 197 | 61011BS00-017-G | - | RES,2.05KOhm,+/-1%,1/16W,G,SMD0402 | KOA SPEER ELECTRONICS, INC. | RK73H1ETTP2051F | 1 | G | PANR26 |  |  |  |  |  |  |
|  |  |  |  |  | 197 | 61011BS00-012-G |  | RES,2.05KOhm,+/-1%,1/16W,G,SMD0402 | WALSIN TECHNOLOGY CORPORATION | WR04X2051FTL |  | G |  |  |  |  |  |  |  |
|  |  |  |  |  | 197 | 61011BS00-011-G |  | RES,2.05KOhm,+/-1%,1/16W,G,SMD0402 | YAGEO CORPORATION COMPONENT | RC0402FR-072K05L |  | G |  |  |  |  |  |  |  |
|  |  |  |  |  | 197 | 61011BS00-044-G |  | RES,2.05KOhm,+/-1%,1/16W,G,SMD0402 | TA-I TECHNOLOGY CO., LTD | RM04FTN2051 |  | G |  |  |  |  |  |  |  |
| Multi | N | Other | Y(4) | 198 | 198 | 610118R00-017-G |  | RES,1.54KOhm,+/-1%,1/16W,G,SMD0402 | KOA SPEER ELECTRONICS, INC. | RK73H1ETTP1541F | 1 | G | PBNR26 |  |  |  |  |  |  |
|  |  |  |  |  | 198 | 610118R00-012-G |  | RES,1.54KOhm,+/-1%,1/16W,G,SMD0402 | WALSIN TECHNOLOGY CORPORATION | WR04X1541FTL |  | G |  |  |  |  |  |  |  |
|  |  |  |  |  | 198 | 610118R00-011-G |  | RES,1.54KOhm,+/-1%,1/16W,G,SMD0402 | YAGEO CORPORATION COMPONENT | RC0402FR-071K54L |  | G |  |  |  |  |  |  |  |
|  |  |  |  |  | 198 | 610118R00-044-G |  | RES,1.54KOhm,+/-1%,1/16W,G,SMD0402 | TA-I TECHNOLOGY CO., LTD | RM04FTN1541 |  | G |  |  |  |  |  |  |  |
| Single | ND |  | N | 199 | 199 | 10128241-112X0LF |  | CONN,PCIE-8X,V/T,Bla,1mm,30u,G,SMD-98 | FCI CONNECTORS HONGKONG LTD. | 10128241-112X0LF | 2 | G | PCIE1,PCIE5 |  |  |  |  |  |  |
| Single | ND |  | N | 200 | 200 | 10128241-113X0LF |  | CONN,PCIE-16X,V/T,Bla,1mm,30u,G,SMD-164 | FCI CONNECTORS HONGKONG LTD. | 10128241-113X0LF | 3 | G | PCIE2,PCIE3,PCIE4 |  |  |  |  |  |  |
| Multi | ND | ND | Y(1) | 201 | 201 | 62011F100-015-G |  | CAP,1uF,+/-10%,X7R,25V,G,SMD0603 | MURATA ELEC. NORTH AMERICA | GRM188R71E105K | 12 | G | PUAC1,PSIC1,PSAC1,PRAC1,PQAC1,PPAC1,PIAC1,PFAC1,PETC1,PERC1,PEAC1,PSUC4 |  |  |  |  |  |  |
|  |  |  |  |  | 201 | 62011F100-023-G |  | CAP,1uF,+/-10%,X7R,25V,G,SMD0603 | TAIYO ELECTRIC IND.CO.LTD | TMK107B7105KA-T |  | G |  |  |  |  |  |  |  |
|  |  |  |  |  | 201 | 62011F100-026-G |  | CAP,1uF,+/-10%,X7R,25V,G,SMD0603 | SAMSUNG SEMICONDUCTOR | CL10B105KA8NNNC |  | G |  |  |  |  |  |  |  |
| Multi | Y | 2 | Y(1) | 202 | 202 | 62011DD00-015-G | - | CAP,22uF,+/-10%,X6S,6.3V,G,SMD1206 | MURATA ELEC. NORTH AMERICA | GRM31CC80J226K | 24 | G | PUAC4,PSAC4,PRAC4,PQAC4,PPAC4,PIAC4,PFAC4,PEAC4,PUAC5,PSAC5,PRAC5,PQAC5,PPAC5,PIAC5,PFAC5,PEAC5,PUAC6,PSAC6,PRAC6,PQAC6,PPAC6,PIAC6,PFAC6,PEAC6 |  |  |  |  |  |  |
|  |  |  |  |  | 202 | 62011DD00-026-G |  | CAP,22uF,+/-10%,X6S,6.3V,G,SMD1206 | SAMSUNG SEMICONDUCTOR | CL31X226KQHNNNE |  | G |  |  |  |  |  |  |  |
| Multi | Y | ND | Y(1) | 203 | 203 | 620119R04-015-G | - | CAP,22uF,+/-20%,X6S,4V,G,SMD0805 | MURATA ELEC. NORTH AMERICA | GRM21BC80G226M | 84 | G | PSLC7,PSFC7,PSEC7,PSDC7,PEEC7,PEDC7,PSLC8,PSFC8,PSEC8,PSDC8,PEEC8,PEDC8,PUAC11,PSLC11,PSIC11,PSFC11,PSEC11,PSDC11,PSAC11,PRAC11,PQAC11,PPAC11,PIAC11,PFAC11,PEEC11,PEDC11,PEAC11,PUAC12,PSLC12,PSIC12,PSFC12,PSEC12,PSDC12,PSAC12,PRAC12,PQAC12,PPAC12,PIAC12,PFAC12,PEEC12,PEDC12,PEAC12,PUAC13,PSIC13,PSAC13,PRAC13,PQAC13,PPAC13,PIAC13,PFAC13,PEAC13,PUAC14,PSIC14,PSAC14,PRAC14,PQAC14,PPAC14,PIAC14,PFAC14,PEAC14,PUAC15,PSLC15,PSIC15,PSFC15,PSEC15,PSDC15,PSAC15,PRAC15,PQAC15,PPAC15,PIAC15,PFAC15,PEEC15,PEDC15,PEAC15,PUAC16,PSIC16,PSAC16,PRAC16,PQAC16,PPAC16,PIAC16,PFAC16,PEAC16 |  |  |  |  |  |  |
|  |  |  |  |  | 203 | 620119R01-015-G |  | CAP,22uF,+/-20%,X6S,4V,G,SMD0805 | MURATA ELEC. NORTH AMERICA | GRM21BC80G226ME39K |  | G |  |  |  |  |  |  |  |
|  |  |  |  |  | 203 | 620119R00-023-G |  | CAP,22uF,+/-20%,X6S,4V,G,SMD0805 | TAIYO ELECTRIC IND.CO.LTD | AMK212C6226MG-T |  | G |  |  |  |  |  |  |  |
|  |  |  |  |  | 203 | 620119R00-026-G |  | CAP,22uF,+/-20%,X6S,4V,G,SMD0805 | SAMSUNG SEMICONDUCTOR | CL21X226MRQNNNE |  | G |  |  |  |  |  |  |  |
| Multi | N |  | Y(3) | 204 | 204 | 62012G600-015-G |  | CAP,2.2uF,+/-10%,X7S,25V,G,SMD0603 | MURATA ELEC. NORTH AMERICA | GRM188C71E225K | 11 | G | PUAC19,PSIC19,PSAC19,PRAC19,PQAC19,PPAC19,PIAC19,PFAC19,PETC19,PERC19,PEAC19 |  |  |  |  |  |  |
|  |  |  |  |  | 204 | 62012G600-012-G |  | CAP,2.2uF,+/-10%,X7S,25V,G,SMD0603 | WALSIN TECHNOLOGY CORPORATION | 0603A225K250CT |  | G |  |  |  |  |  |  |  |
| Multi | ND |  | N | 205 | 205 | 630335M00-088-G |  | IND,820nH@100KHz,+/-20%,13A,8mOhm,SHLD,G,SMD | COOPER BUSSMANN, INC. | HCM0703-R82-R | 8 | G | PUAL1,PSAL1,PRAL1,PQAL1,PPAL1,PIAL1,PFAL1,PEAL1 |  |  |  |  |  |  |
|  |  |  |  |  | 205 | 63035Y800-051-G |  | Coil Ind,Shielded(SHLD),820nH@100KHz,+/-20%,13A,8mOhm,SMD,7.6*6.9*3.0,,,G | PULSE ELECTRONICS (SINGAPORE) | PA4341.821NLT |  | G |  |  |  |  |  |  |  |
|  |  |  |  |  | 205 | 63032RP05-129-G |  | IND,820nH@100KHz,+/-20%,13A,8mOhm,SHLD,G,SMD | MAG.LAYERS, SCIENTIFIC-TECHNICS (KUNSHAN) CO., LTD. | SPS-06CZ-R82M-V1 |  | G |  |  |  |  |  |  |  |
| Multi | ND | ND | Y(4) | 206 | 206 | 610114200-017-G |  | RES,10.7KOhm,+/-1%,1/16W,G,SMD0402 | KOA SPEER ELECTRONICS, INC. | RK73H1ETTP1072F | 8 | G | PUAR2,PSAR2,PRAR2,PQAR2,PPAR2,PIAR2,PFAR2,PEAR2 |  |  |  |  |  |  |
|  |  |  |  |  | 206 | 610114200-012-G |  | RES,10.7KOhm,+/-1%,1/16W,G,SMD0402 | WALSIN TECHNOLOGY CORPORATION | WR04X1072FTL |  | G |  |  |  |  |  |  |  |
|  |  |  |  |  | 206 | 610114200-011-G |  | RES,10.7KOhm,+/-1%,1/16W,G,SMD0402 | YAGEO CORPORATION COMPONENT | RC0402FR-0710K7L |  | G |  |  |  |  |  |  |  |
|  |  |  |  |  | 206 | 610114200-044-G |  | RES,10.7KOhm,+/-1%,1/16W,G,SMD0402 | TA-I TECHNOLOGY CO., LTD | RM04FTN1072 |  | G |  |  |  |  |  |  |  |
| Multi | N |  | Y(2) | 207 | 207 | 611004D00-017-G |  | RES,1.5KOhm,+/-0.1%,1/16W,G,SMD0402 | KOA SPEER ELECTRONICS, INC. | RN731ETTP1501B25 | 16 | G | PUAR4,PSAR4,PRAR4,PQAR4,PPAR4,PIAR4,PFAR4,PEAR4,PUAR6,PSAR6,PRAR6,PQAR6,PPAR6,PIAR6,PFAR6,PEAR6 |  |  |  |  |  |  |
|  |  |  |  |  | 207 | 611004D01-011-G |  | RES,1.5KOhm,+/-0.1%,1/16W,G,SMD0402 | YAGEO CORPORATION COMPONENT | RT0402BRD071K5L |  | G |  |  |  |  |  |  |  |
| Multi | N | Other | N | 208 | 208 | 61011JY00-017-G | - | RES,39.2KOhm,+/-1%,1/16W,G,SMD0402 | KOA SPEER ELECTRONICS, INC. | RK73H1ETTP3922F | 11 | G | PUAR5,PSIR5,PSAR5,PRAR5,PQAR5,PPAR5,PIAR5,PFAR5,PETR5,PERR5,PEAR5 |  |  |  |  |  |  |
|  |  |  |  |  | 208 | 61011JY00-012-G |  | RES,39.2KOhm,+/-1%,1/16W,G,SMD0402 | WALSIN TECHNOLOGY CORPORATION | WR04X3922FTL |  | G |  |  |  |  |  |  |  |
|  |  |  |  |  | 208 | 61011JY00-011-G |  | RES,39.2KOhm,+/-1%,1/16W,G,SMD0402 | YAGEO CORPORATION COMPONENT | RC0402FR-0739K2L |  | G |  |  |  |  |  |  |  |
|  |  |  |  |  | 208 | 61011JY00-044-G |  | RES,39.2KOhm,+/-1%,1/16W,G,SMD0402 | TA-I TECHNOLOGY CO., LTD | RM04FTN3922 |  | G |  |  |  |  |  |  |  |
|  |  |  |  |  | 208 | 61011JY00-029-G |  | RES,39.2KOhm,+/-1%,1/16W,G,SMD0402 | VISHAY ENTER TECHNO LOGY.INC | CRCW040239K2FKED |  | G |  |  |  |  |  |  |  |
| Multi | ND | ND | Y(4) | 209 | 209 | 610117F00-017-G | - | RES,5.76KOhm,+/-1%,1/16W,G,SMD0402 | KOA SPEER ELECTRONICS, INC. | RK73H1ETTP5761F | 16 | G | PUAR8,PSAR8,PRAR8,PQAR8,PPAR8,PIAR8,PFAR8,PEAR8,PUAR11,PSAR11,PRAR11,PQAR11,PPAR11,PIAR11,PFAR11,PEAR11 |  |  |  |  |  |  |
|  |  |  |  |  | 209 | 610117F00-012-G |  | RES,5.76KOhm,+/-1%,1/16W,G,SMD0402 | WALSIN TECHNOLOGY CORPORATION | WR04X5761FTL |  | G |  |  |  |  |  |  |  |
|  |  |  |  |  | 209 | 610117F00-011-G |  | RES,5.76KOhm,+/-1%,1/16W,G,SMD0402 | YAGEO CORPORATION COMPONENT | RC0402FR-075K76L |  | G |  |  |  |  |  |  |  |
|  |  |  |  |  | 209 | 610117F00-044-G |  | RES,5.76KOhm,+/-1%,1/16W,G,SMD0402 | TA-I TECHNOLOGY CO., LTD | RM04FTN5761 |  | G |  |  |  |  |  |  |  |
| Multi | N | ND | Y(4) | 210 | 210 | 610128200-017-G | - | RES,26.1 Ohm,+/-1%,1/16W,G,SMD0402 | KOA SPEER ELECTRONICS, INC. | RK73H1ETTP26R1F | 8 | G | PUAR10,PSAR10,PRAR10,PQAR10,PPAR10,PIAR10,PFAR10,PEAR10 |  |  |  |  |  |  |
|  |  |  |  |  | 210 | 610128200-012-G |  | RES,26.1 Ohm,+/-1%,1/16W,G,SMD0402 | WALSIN TECHNOLOGY CORPORATION | WR04X26R1FTL |  | G |  |  |  |  |  |  |  |
|  |  |  |  |  | 210 | 610128200-011-G |  | RES,26.1 Ohm,+/-1%,1/16W,G,SMD0402 | YAGEO CORPORATION COMPONENT | RC0402FR-0726R1L |  | G |  |  |  |  |  |  |  |
|  |  |  |  |  | 210 | 610128200-044-G |  | RES,26.1 Ohm,+/-1%,1/16W,G,SMD0402 | TA-I TECHNOLOGY CO., LTD | RM04FTN26R1 |  | G |  |  |  |  |  |  |  |
| Single | Y |  | N | 211 | 211 | 32012NN00-238-G |  | IC,Regulator,IR3898MTRPBF,6A,1.5MHZ,G,QFN-17,SMD | INTERNATIONAL RECTIFIER | IR3898MTRPBF | 11 | G | PUAU1,PSIU1,PSAU1,PRAU1,PQAU1,PPAU1,PIAU1,PFAU1,PETU1,PERU1,PEAU1 |  |  |  |  |  |  |
| Multi | N |  | Y(1) | 212 | 212 | 62012T300-015-G |  | CAP,1uF,+/-10%,X7S,25V,G,SMD0402 | MURATA ELEC. NORTH AMERICA | GRM155C71E105KE11D | 14 | G | PSTC4,PSLC4,PSFC4,PSEC4,PSDC4,PQPC4,PFRC4,PEEC4,PEDC4,PSPC3003,PIPC3003,PFPC3003,PEPC3003,PSRC3010 |  |  |  |  |  |  |
|  |  |  |  |  | 212 | 620138700-026-G |  | CAP,1uF,+/-10%,X6S,25V,G,SMD0402 | SAMSUNG SEMICONDUCTOR | CL05X105KA5NQNC |  | G |  |  |  |  |  |  |  |
|  |  |  |  |  | 212 | 620138700-015-G |  | CAP,1uF,+/-10%,X6S,25V,G,SMD0402 | MURATA ELEC. NORTH AMERICA | GRM155C81E105KE11D |  | G |  |  |  |  |  |  |  |
| Multi | N |  | Y(3) | 213 | 213 | 62012CM01-015-G |  | CAP,10uF,+/-20%,X6S,4V,G,SMD0603 | MURATA ELEC. NORTH AMERICA | GRM188C80G106M | 6 | G | PSLC16,PSFC16,PSEC16,PSDC16,PEEC16,PEDC16 |  |  |  |  |  |  |
|  |  |  |  |  | 213 | 62012CM00-023-G |  | CAP,10uF,+/-20%,X6S,4V,G,SMD0603 | TAIYO ELECTRIC IND.CO.LTD | AMK107AC6106MA-T |  | G |  |  |  |  |  |  |  |
|  |  |  |  |  | 213 | 62012CM00-026-G |  | CAP,10uF,+/-20%,X6S,4V,G,SMD0603 | SAMSUNG SEMICONDUCTOR | CL10X106MR8NNNC |  | G |  |  |  |  |  |  |  |
| Multi | ND | ND | N | 214 | 214 | 63032CD00-088-G | - | IND,2.2uH@100KHz,+/-20%,8A,20mOhm,SHLD,G,SMD | COOPER BUSSMANN, INC. | HCM0703-2R2-R | 5 | G | PETL1,PERL1,PSFL2,PEEL2,PEDL2 |  |  |  |  |  |  |
|  |  |  |  |  | 214 | 63033JK00-15A-G |  | IND,2.2uH@100KHz,+/-20%,9A,16.5mOhm,SHLD,G,SMD | The Inter-Technical Group, Inc. | SMHC2511A-2R2MHF |  | G |  |  |  |  |  |  |  |
| Multi | ND | ND | Y(4) | 215 | 215 | 61011HA00-017-G |  | RES,1 Ohm,+/-1%,1/16W,G,SMD0402 | KOA SPEER ELECTRONICS, INC. | RK73H1ETTP1R00F | 13 | G | PSPR4,PIPR4,PFPR4,PEPR4,PSTR5,PSLR5,PSFR5,PSER5,PSDR5,PQPR5,PFRR5,PEER5,PEDR5 |  |  |  |  |  |  |
|  |  |  |  |  | 215 | 61011HA00-012-G |  | RES,1 Ohm,+/-1%,1/16W,G,SMD0402 | WALSIN TECHNOLOGY CORPORATION | WR04W1R00FTL |  | G |  |  |  |  |  |  |  |
|  |  |  |  |  | 215 | 61011HA00-011-G |  | RES,1 Ohm,+/-1%,1/16W,G,SMD0402 | YAGEO CORPORATION COMPONENT | RC0402FR-071RL |  | G |  |  |  |  |  |  |  |
|  |  |  |  |  | 215 | 61011HA00-044-G |  | RES,1 Ohm,+/-1%,1/16W,G,SMD0402 | TA-I TECHNOLOGY CO., LTD | RM04FTN1R00 |  | G |  |  |  |  |  |  |  |
|  |  |  |  |  | 215 | 61011HA00-029-G |  | RES,1 Ohm,+/-1%,1/16W,G,SMD0402 | VISHAY ENTER TECHNO LOGY.INC | CRCW04021R00FNED |  | G |  |  |  |  |  |  |  |
| Multi | N |  | N | 216 | 216 | 611004M00-017-G |  | RES,16.5KOhm,+/-0.1%,1/16W,G,SMD0402 | KOA SPEER ELECTRONICS, INC. | RN731ETTP1652B25 | 9 | G | PSLR17,PSFR17,PSER17,PSDR17,PQPR17,PFRR17,PEER17,PEDR17,PEDR19 |  |  |  |  |  |  |
|  |  |  |  |  | 216 | 611004M00-024-G |  | RES,16.5KOhm,+/-0.1%,1/16W,G,SMD0402 | PANASONIC INDUSTRIAL CO.,LTD. | ERA2AEB1652X |  | G |  |  |  |  |  |  |  |
| Single | ND |  | ND | 217 | 217 | 32013PD00-238-G |  | IC,Regulator,IR3883MTRPbF,ADJ,3A,G,QFN-16,SMD | INTERNATIONAL RECTIFIER | IR3883MTRPBF | 9 | G | PSTU1,PSLU1,PSFU1,PSEU1,PSDU1,PQPU1,PFRU1,PEEU1,PEDU1 |  |  |  |  |  |  |
| Multi | ND | ND | Y(5) | 218 | 218 | 611003400-017-G |  | RES,12.7KOhm,+/-0.1%,1/16W,G,SMD0402 | KOA SPEER ELECTRONICS, INC. | RN731ETTP1272B25 | 1 | G | PEER19 |  |  |  |  |  |  |
|  |  |  |  |  | 218 | 61013AS00-012-G |  | RES,12.7KOhm,+/-0.1%,1/16W,G,SMD0402 | WALSIN TECHNOLOGY CORPORATION | WF04H1272BTL |  | G |  |  |  |  |  |  |  |
|  |  |  |  |  | 218 | 611003400-011-G |  | RES,12.7KOhm,+/-0.1%,1/16W,G,SMD0402 | YAGEO CORPORATION COMPONENT | RT0402BRD0712K7L |  | G |  |  |  |  |  |  |  |
|  |  |  |  |  | 218 | 611003400-024-G |  | RES,12.7KOhm,+/-0.1%,1/16W,G,SMD0402 | PANASONIC INDUSTRIAL CO.,LTD. | ERA2AEB1272X |  | G |  |  |  |  |  |  |  |
|  |  |  |  |  | 218 | 611003400-029-G |  | RES,12.7KOhm,+/-0.1%,1/16W,G,SMD0402 | VISHAY ENTER TECHNO LOGY.INC | TNPW040212K7BEED |  | G |  |  |  |  |  |  |  |
| Multi | N |  | N | 219 | 219 | 62120HJ00-022-G |  | ECAP,SPEA,270uF,+/-20%,16V,105C,G,SMD6.3X9.9,ESR<=8mOhm | SANYO ELECTRIC CO., LTD. | 16SVPG270M | 5 | G | PSPCE1,PIPCE1,PFPCE1,PEPCE1,PSUCE4 |  |  |  |  |  |  |
|  |  |  |  |  | 219 | 62120LS00-021-G |  | ECAP,Solid Polymer Electrolytic Aluminium Capacitor (SPEA),Low ESR(LESR),270uF,+/-20%,16V,105_x0003_,10mOhm,SMD,6.3*7.7,G | NIPPON CHEMI-CON CORPORATION | APXJ160ARA271MF80J |  | G |  |  |  |  |  |  |  |
| Single | N | Other | Y(1) | 220 | 220 | 62120CM00-024-G | - | SPEA CAP,220uF,+10%~-35%,6.3V,105C,G,SMD2816,ESR<=15mOhm | PANASONIC INDUSTRIAL CO.,LTD. | EEFCX0J221YR | 14 | G | PSRCE3000,PSRCE3001,PSPCE3003,PIPCE3003,PFPCE3003,PEPCE3003,PSPCE3004,PIPCE3004,PFPCE3004,PEPCE3004,PSPCE3005,PIPCE3005,PFPCE3005,PEPCE3005 |  |  |  |  |  |  |
| Multi | Y | 2 | Y(3) | 221 | 221 | 62010FF00-015-G | - | CAP,47pF,+/-5%,NPO(C0G),50V,G,SMD0402 | MURATA ELEC. NORTH AMERICA | GRM1555C1H470J | 4 | G | PSPC11,PIPC11,PFPC11,PEPC11 |  |  |  |  |  |  |
|  |  |  |  |  | 221 | 62010FF06-012-G |  | CAP,47pF,+/-5%,NPO(C0G),50V,G,SMD0402 | WALSIN TECHNOLOGY CORPORATION | 0402N470J500CT |  | G |  |  |  |  |  |  |  |
|  |  |  |  |  | 221 | 62010FF00-026-G |  | CAP,47pF,+/-5%,NPO(C0G),50V,G,SMD0402 | SAMSUNG SEMICONDUCTOR | CL05C470JB5NNNC |  | G |  |  |  |  |  |  |  |
|  |  |  |  |  | 221 | 62010FF00-023-G |  | CAP,47pF,+/-5%,NPO(C0G),50V,G,SMD0402 | TAIYO ELECTRIC IND.CO.LTD | UMK105CG470JV-F |  | G |  |  |  |  |  |  |  |
| Multi | N |  | N | 222 | 222 | 63032CC00-088-G |  | IND,1uH@100KHz,+/-20%,11A,10mOhm,SHLD,G,SMD | COOPER BUSSMANN, INC. | HCM0703-1R0-R | 4 | G | PSPL1,PIPL1,PFPL1,PEPL1 |  |  |  |  |  |  |
|  |  |  |  |  | 222 | 63035CF00-034-G |  | IND,1uH@100KHz,+/-20%,10A,10mOhm,SHLD,G,SMD | CYNTEC CO. LTD | CMMS063T-1R0MS |  | G |  |  |  |  |  |  |  |
|  |  |  |  |  | 222 | 630362F00-051-G |  | IND,22nH@100KHz,+/-20%,19A,368uOhm,SHLD,G,SMD | PULSE ELECTRONICS (SINGAPORE) | PA4341.102NLT |  | G |  |  |  |  |  |  |  |
| Multi | ND |  | N | 223 | 223 | 630341400-088-G |  | IND,22nH@1MHz,+/-20%,19A,368uOhm,SHLD,G,SMD | COOPER BUSSMANN, INC. | FP0404R1-R022-R | 4 | G | PSPL2,PIPL2,PFPL2,PEPL2 |  |  |  |  |  |  |
|  |  |  |  |  | 223 | 630362G00-065-G |  | IND,22nH@100KHz,+/-20%,19A,0.32mOhm,SHLD,G,SMD | DELTA ELECTRONICS INDUSTRIAL CO.,LTD | HCB0430-220 |  | G |  |  |  |  |  |  |  |
| Multi | ND | ND | Y(4) | 224 | 224 | 61011H300-017-G |  | RES,316 Ohm,+/-1%,1/16W,G,SMD0402 | KOA SPEER ELECTRONICS, INC. | RK73H1ETTP3160F | 4 | G | PSPR5,PIPR5,PFPR5,PEPR5 |  |  |  |  |  |  |
|  |  |  |  |  | 224 | 61011H300-012-G |  | RES,316 Ohm,+/-1%,1/16W,G,SMD0402 | WALSIN TECHNOLOGY CORPORATION | WR04X3160FTL |  | G |  |  |  |  |  |  |  |
|  |  |  |  |  | 224 | 61011H300-011-G |  | RES,316 Ohm,+/-1%,1/16W,G,SMD0402 | YAGEO CORPORATION COMPONENT | RC0402FR-07316RL |  | G |  |  |  |  |  |  |  |
| Multi | ND | ND | Y(4) | 225 | 225 | 610116R00-017-G | - | RES,14.3KOhm,+/-1%,1/16W,G,SMD0402 | KOA SPEER ELECTRONICS, INC. | RK73H1ETTP1432F | 7 | G | PSPR9,PIPR9,PFPR9,PEPR9,R1074,R1083,R1777 |  |  |  |  |  |  |
|  |  |  |  |  | 225 | 610116R00-012-G |  | RES,14.3KOhm,+/-1%,1/16W,G,SMD0402 | WALSIN TECHNOLOGY CORPORATION | WR04X1432FTL |  | G |  |  |  |  |  |  |  |
|  |  |  |  |  | 225 | 610116R00-011-G |  | RES,14.3KOhm,+/-1%,1/16W,G,SMD0402 | YAGEO CORPORATION COMPONENT | RC0402FR-0714K3L |  | G |  |  |  |  |  |  |  |
|  |  |  |  |  | 225 | 610116R00-044-G |  | RES,14.3KOhm,+/-1%,1/16W,G,SMD0402 | TA-I TECHNOLOGY CO., LTD | RM04FTN1432 |  | G |  |  |  |  |  |  |  |
|  |  |  |  |  | 225 | 610116R00-029-G |  | RES,14.3KOhm,+/-1%,1/16W,G,SMD0402 | VISHAY ENTER TECHNO LOGY.INC | CRCW040214K3FKED |  | G |  |  |  |  |  |  |  |
| Multi | N |  | Y(5) | 226 | 226 | 61100QQ00-017-G |  | RES,9.76KOhm,+/-0.1%,1/16W,G,SMD0402 | KOA SPEER ELECTRONICS, INC. | RN731ETTP9761B25 | 4 | G | PSPR10,PIPR10,PFPR10,PEPR10 |  |  |  |  |  |  |
|  |  |  |  |  | 226 | 61100QQ00-024-G |  | RES,9.76KOhm,+/-0.1%,1/16W,G,SMD0402 | PANASONIC INDUSTRIAL CO.,LTD. | ERA2AEB9761X |  | G |  |  |  |  |  |  |  |
|  |  |  |  |  | 226 | 61100QQ00-029-G |  | RES,9.76KOhm,+/-0.1%,1/16W,G,SMD0402 | VISHAY ENTER TECHNO LOGY.INC | TNPW04029K76BEED |  | G |  |  |  |  |  |  |  |
| Multi | N | ND | Y(4) | 227 | 227 | 610112J00-017-G | - | RES,200 Ohm,+/-1%,1/16W,G,SMD0402 | KOA SPEER ELECTRONICS, INC. | RK73H1ETTP2000F | 14 | G | PSPR11,PIPR11,PFPR11,PEPR11,R680,R688,R689,R755,R756,R758,R759,R771,R1487,R1541 |  |  |  |  |  |  |
|  |  |  |  |  | 227 | 610112J00-012-G |  | RES,200 Ohm,+/-1%,1/16W,G,SMD0402 | WALSIN TECHNOLOGY CORPORATION | WR04X2000FTL |  | G |  |  |  |  |  |  |  |
|  |  |  |  |  | 227 | 610112J00-011-G |  | RES,200 Ohm,+/-1%,1/16W,G,SMD0402 | YAGEO CORPORATION COMPONENT | RC0402FR-07200RL |  | G |  |  |  |  |  |  |  |
|  |  |  |  |  | 227 | 610112J00-044-G |  | RES,200 Ohm,+/-1%,1/16W,G,SMD0402 | TA-I TECHNOLOGY CO., LTD | RM04FTN2000 |  | G |  |  |  |  |  |  |  |
|  |  |  |  |  | 227 | 610112J00-029-G |  | RES,200 Ohm,+/-1%,1/16W,G,SMD0402 | VISHAY ENTER TECHNO LOGY.INC | CRCW0402200RFKED |  | G |  |  |  |  |  |  |  |
|  |  |  |  |  | 227 | 610112J00-024-G |  | RES,200 Ohm,+/-1%,1/16W,G,SMD0402 | PANASONIC INDUSTRIAL CO.,LTD. | ERJ2RKF2000X |  | G |  |  |  |  |  |  |  |
| Multi | N | Other | Y(4) | 228 | 228 | 61011MU00-017-G |  | RES,48.7KOhm,+/-1%,1/16W,G,SMD0402 | KOA SPEER ELECTRONICS, INC. | RK73H1ETTP4872F | 5 | G | PSRR7,PSPR15,PIPR15,PFPR15,PEPR15 |  |  |  |  |  |  |
|  |  |  |  |  | 228 | 61011MU00-012-G |  | RES,48.7KOhm,+/-1%,1/16W,G,SMD0402 | WALSIN TECHNOLOGY CORPORATION | WR04X4872FTL |  | G |  |  |  |  |  |  |  |
|  |  |  |  |  | 228 | 61011MU00-011-G |  | RES,48.7KOhm,+/-1%,1/16W,G,SMD0402 | YAGEO CORPORATION COMPONENT | RC0402FR-0748K7L |  | G |  |  |  |  |  |  |  |
|  |  |  |  |  | 228 | 61011MU00-044-G |  | RES,48.7KOhm,+/-1%,1/16W,G,SMD0402 | TA-I TECHNOLOGY CO., LTD | RM04FTN4872 |  | G |  |  |  |  |  |  |  |
|  |  |  |  |  | 228 | 61011MU00-029-G |  | RES,48.7KOhm,+/-1%,1/16W,G,SMD0402 | VISHAY ENTER TECHNO LOGY.INC | CRCW040248K7FKED |  | G |  |  |  |  |  |  |  |
| Single | ND |  | N | 229 | 229 | 32013HH00-238-G |  | IC,Regulator,IR3447MTRPBF,ADJ,25A,G,PQFN-33 | INTERNATIONAL RECTIFIER | IR3447MTRPBF | 4 | G | PSPU1,PIPU1,PFPU1,PEPU1 |  |  |  |  |  |  |
| Multi | N |  | N | 230 | 230 | 62011M802-015-G |  | CAP,62pF,+/-5%,NPO(C0G),50V,G,SMD0402 | MURATA ELEC. NORTH AMERICA | GRM1555C1H620JA01D | 2 | G | PSRC3,PERC3 |  |  |  |  |  |  |
|  |  |  |  |  | 230 | 62011M800-011-G |  | CAP,62pF,+/-5%,NPO(C0G),50V,G,SMD0402 | YAGEO CORPORATION COMPONENT | CC0402JRNPO9BN620 |  | G |  |  |  |  |  |  |  |
|  |  |  |  |  | 230 | 62011M800-026-G |  | CAP,MLCC,62pF,+/-5%,NPO(C0G),50V,SMD0402,G | SAMSUNG SEMICONDUCTOR | CL05C620JB5NNNC |  | G |  |  |  |  |  |  |  |
| Multi | N |  | N | 231 | 231 | 62013BP00-015-G |  | CAP,22uF,+/-20%,X6S,25V,G,SMD1206 | MURATA ELEC. NORTH AMERICA | GRM31CC81E226ME11L | 10 | G | PSIC4,PETC4,PERC4,PSIC5,PETC5,PERC5,PSIC6,PETC6,PERC6,PETC22 |  |  |  |  |  |  |
|  |  |  |  |  | 231 | 62013BP00-011-G |  | CAP,22uF,+/-20%,X6S,25V,G,SMD1206 | YAGEO CORPORATION COMPONENT | CC1206MKX6S8BB226 |  | G |  |  |  |  |  |  |  |
| Multi | N |  | N | 232 | 232 | 62013BN00-015-G |  | CAP,4.3nF,+/-10%,X7R,50V,G,SMD0402 | MURATA ELEC. NORTH AMERICA | GRM155R71H432KA01D | 1 | G | PERC7 |  |  |  |  |  |  |
|  |  |  |  |  | 232 | 62010LJ00-023-G |  | CAP,4.7nF,+/-10%,X7R,50V,G,SMD0402 | TAIYO ELECTRIC IND.CO.LTD | UMK105B7472KV-F |  | G |  |  |  |  |  |  |  |
| Multi | N |  | Y(1) | 233 | 233 | 62012PT00-015-G |  | CAP,22uF,+/-20%,X6S,16V,G,SMD0805 | MURATA ELEC. NORTH AMERICA | GRM21BC81C226M | 35 | G | PSTC7,PQPC7,PFRC7,PSTC8,PQPC8,PFRC8,PSRC10,PSTC11,PSRC11,PQPC11,PFRC11,PETC11,PERC11,PSTC12,PSRC12,PQPC12,PFRC12,PETC12,PERC12,PSRC13,PETC13,PERC13,PETC14,PERC14,PSTC15,PQPC15,PFRC15,PETC15,PERC15,PETC16,PERC16,PSRC3012,PSRC3013,PSRC3014,PSRC3015 |  |  |  |  |  |  |
|  |  |  |  |  | 233 | 62012PT00-023-G |  | CAP,22uF,+/-20%,X6S,16V,G,SMD0805 | TAIYO ELECTRIC IND.CO.LTD | EDK212BC6226MG-T |  | G |  |  |  |  |  |  |  |
| Multi | ND | ND | Y(4) | 234 | 234 | 61011PE00-017-G |  | RES,8.87KOhm,+/-1%,1/16W,G,SMD0402 | KOA SPEER ELECTRONICS, INC. | RK73H1ETTP8871F | 1 | G | PERR2 |  |  |  |  |  |  |
|  |  |  |  |  | 234 | 61011PE00-012-G |  | RES,8.87KOhm,+/-1%,1/16W,G,SMD0402 | WALSIN TECHNOLOGY CORPORATION | WR04X8871FTL |  | G |  |  |  |  |  |  |  |
|  |  |  |  |  | 234 | 61011PE00-011-G |  | RES,8.87KOhm,+/-1%,1/16W,G,SMD0402 | YAGEO CORPORATION COMPONENT | RC0402FR-078K87L |  | G |  |  |  |  |  |  |  |
|  |  |  |  |  | 234 | 61011PE00-044-G |  | RES,8.87KOhm,+/-1%,1/16W,G,SMD0402 | TA-I TECHNOLOGY CO., LTD | RM04FTN8871 |  | G |  |  |  |  |  |  |  |
| Multi | N |  | Y(5) | 235 | 235 | 61100JA00-017-G |  | RES,8.66KOhm,+/-0.1%,1/16W,G,SMD0402 | KOA SPEER ELECTRONICS, INC. | RN731ETTP8661B25 | 2 | G | PERR8,PERR11 |  |  |  |  |  |  |
|  |  |  |  |  | 235 | 61100JA00-011-G |  | RES,8.66KOhm,+/-0.1%,1/16W,G,SMD0402 | YAGEO CORPORATION COMPONENT | RT0402BRD078K66L |  | G |  |  |  |  |  |  |  |
|  |  |  |  |  | 235 | 61100JA00-044-G |  | RES,8.66KOhm,+/-0.1%,1/16W,G,SMD0402 | TA-I TECHNOLOGY CO., LTD | RB04BTP8661 |  | G |  |  |  |  |  |  |  |
|  |  |  |  |  | 235 | 61100JA00-024-G |  | RES,8.66KOhm,+/-0.1%,1/16W,G,SMD0402 | PANASONIC INDUSTRIAL CO.,LTD. | ERA2AEB8661X |  | G |  |  |  |  |  |  |  |
|  |  |  |  |  | 235 | 61100JA00-029-G |  | RES,8.66KOhm,+/-0.1%,1/16W,G,SMD0402 | VISHAY ENTER TECHNO LOGY.INC | TNPW04028K66BEED |  | G |  |  |  |  |  |  |  |
|  |  |  |  |  | 235 | 61100JA00-012-G |  | RES,8.66KOhm,+/-0.1%,1/16W,G,SMD0402 | WALSIN TECHNOLOGY CORPORATION | WF04U8661BTL |  | G |  |  |  |  |  |  |  |
| Multi | N |  | Y(4) | 236 | 236 | 61015JF00-017-G |  | RES,63.4 Ohm,+/-1%,1/10W,G,SMD0402 | KOA SPEER ELECTRONICS, INC. | RK73H1ETTP63R4F | 4 | G | PSIR10,PETR10,PERR10,R938 |  |  |  |  |  |  |
|  |  |  |  |  | 236 | 61015JF00-044-G |  | RES,thick film,63.4Ohm,+/-1%,1/10W,SMD0402,G | TA-I TECHNOLOGY CO., LTD | RMH04FT63R4 |  | G |  |  |  |  |  |  |  |
| Multi | N |  | Y(5) | 237 | 237 | 61100PW00-017-G |  | RES,1.54KOhm,+/-0.1%,1/16W,G,SMD0402 | KOA SPEER ELECTRONICS, INC. | RN731ETTP1541B25 | 2 | G | PERR13,PERR15 |  |  |  |  |  |  |
|  |  |  |  |  | 237 | 61100PW00-024-G |  | RES,1.54KOhm,+/-0.1%,1/16W,G,SMD0402 | PANASONIC INDUSTRIAL CO.,LTD. | ERA2AEB1541X |  | G |  |  |  |  |  |  |  |
|  |  |  |  |  | 237 | 61100PW00-029-G |  | RES,1.54KOhm,+/-0.1%,1/16W,G,SMD0402 | VISHAY ENTER TECHNO LOGY.INC | TNPW04021K54BEED |  | G |  |  |  |  |  |  |  |
| Multi | N |  | N | 238 | 238 | 62011LT01-015-G |  | CAP,130pF,+/-5%,NPO(C0G),50V,G,SMD0402 | MURATA ELEC. NORTH AMERICA | GRM1555C1H131JA01D | 1 | G | PETC3 |  |  |  |  |  |  |
|  |  |  |  |  | 238 | 62011LT00-011-G |  | CAP,130pF,+/-5%,NPO(C0G),50V,G,SMD0402 | YAGEO CORPORATION COMPONENT | CC0402JRNPO9BN131 |  | G |  |  |  |  |  |  |  |
|  |  |  |  |  | 238 | 62011LT00-012-G |  | CAP,130pF,+/-5%,NPO(C0G),50V,G,SMD0402 | WALSIN TECHNOLOGY CORPORATION | 0402N131J500LT |  | G |  |  |  |  |  |  |  |
| Multi | ND | ND | Y(3) | 239 | 239 | 62011AM00-015-G | - | CAP,6.8nF,+/-10%,X7R,50V,G,SMD0402 | MURATA ELEC. NORTH AMERICA | GRM155R71H682K | 1 | G | PETC7 |  |  |  |  |  |  |
|  |  |  |  |  | 239 | 62011AM00-012-G |  | CAP,6.8nF,+/-10%,X7R,50V,G,SMD0402 | WALSIN TECHNOLOGY CORPORATION | 0402B682K500CT |  | G |  |  |  |  |  |  |  |
|  |  |  |  |  | 239 | 62011AM00-026-G |  | CAP,6.8nF,+/-10%,X7R,50V,G,SMD0402 | SAMSUNG SEMICONDUCTOR | CL05B682KB5NNNC |  | G |  |  |  |  |  |  |  |
| Multi | N | ND | Y(4) | 240 | 240 | 61011KY00-017-G |  | RES,3.83KOhm,+/-1%,1/16W,G,SMD0402 | KOA SPEER ELECTRONICS, INC. | RK73H1ETTP3831F | 1 | G | PETR2 |  |  |  |  |  |  |
|  |  |  |  |  | 240 | 61011KY00-012-G |  | RES,3.83KOhm,+/-1%,1/16W,G,SMD0402 | WALSIN TECHNOLOGY CORPORATION | WR04X3831FTL |  | G |  |  |  |  |  |  |  |
|  |  |  |  |  | 240 | 61011KY00-011-G |  | RES,3.83KOhm,+/-1%,1/16W,G,SMD0402 | YAGEO CORPORATION COMPONENT | RC0402FR-073K83L |  | G |  |  |  |  |  |  |  |
|  |  |  |  |  | 240 | 61011KY00-044-G |  | RES,3.83KOhm,+/-1%,1/16W,G,SMD0402 | TA-I TECHNOLOGY CO., LTD | RM04FTN3831 |  | G |  |  |  |  |  |  |  |
|  |  |  |  |  | 240 | 61011KY00-029-G |  | RES,3.83KOhm,+/-1%,1/16W,G,SMD0402 | VISHAY ENTER TECHNO LOGY.INC | CRCW04023K83FKED |  | G |  |  |  |  |  |  |  |
| Multi | N |  | Y(5) | 241 | 241 | 611007000-017-G |  | RES,8.25KOhm,+/-0.1%,1/16W,G,SMD0402 | KOA SPEER ELECTRONICS, INC. | RN731ETTP8251B25 | 4 | G | PSIR8,PETR8,PSIR11,PETR11 |  |  |  |  |  |  |
|  |  |  |  |  | 241 | 611007000-011-G |  | RES,8.25KOhm,+/-0.1%,1/16W,G,SMD0402 | YAGEO CORPORATION COMPONENT | RT0402BRD078K25L |  | G |  |  |  |  |  |  |  |
|  |  |  |  |  | 241 | 611007000-012-G |  | RES,8.25KOhm,+/-0.1%,1/16W,G,SMD0402 | WALSIN TECHNOLOGY CORPORATION | WF04U8251BTL |  | G |  |  |  |  |  |  |  |
| Multi | ND | ND | Y(5) | 242 | 242 | 61100AW00-017-G |  | RES,909 Ohm,+/-0.1%,1/16W,G,SMD0402 | KOA SPEER ELECTRONICS, INC. | RN731ETTP9090B25 | 2 | G | PETR13,PETR15 |  |  |  |  |  |  |
|  |  |  |  |  | 242 | 61100AW00-024-G |  | RES,909 Ohm,+/-0.1%,1/16W,G,SMD0402 | PANASONIC INDUSTRIAL CO.,LTD. | ERA2AEB9090X |  | G |  |  |  |  |  |  |  |
|  |  |  |  |  | 242 | 61100AW00-029-G |  | RES,909 Ohm,+/-0.1%,1/16W,G,SMD0402 | VISHAY ENTER TECHNO LOGY.INC | TNPW0402909RBEED |  | G |  |  |  |  |  |  |  |
| Multi | Y | 2 | Y(3) | 243 | 243 | 620105U00-015-G | - | CAP,220pF,+/-10%,X7R,50V,G,SMD0402 | MURATA ELEC. NORTH AMERICA | GRM155R71H221K | 3 | G | PSTC14,PQPC14,PFRC14 |  |  |  |  |  |  |
|  |  |  |  |  | 243 | 620105U00-012-G |  | CAP,220pF,+/-10%,X7R,50V,G,SMD0402 | WALSIN TECHNOLOGY CORPORATION | 0402B221K500CT |  | G |  |  |  |  |  |  |  |
|  |  |  |  |  | 243 | 620105U00-026-G |  | CAP,220pF,+/-10%,X7R,50V,G,SMD0402 | SAMSUNG SEMICONDUCTOR | CL05B221KB5NNNC |  | G |  |  |  |  |  |  |  |
| Multi | N |  | N | 244 | 244 | 63032PP00-088-G |  | IND,4.7uH@100KHz,+/-20%,5.5A,40mOhm,SHLD,G,SMD | COOPER BUSSMANN, INC. | HCM0703-4R7-R | 2 | G | PQPL2,PFRL2 |  |  |  |  |  |  |
|  |  |  |  |  | 244 | 63030PW00-034-G |  | Coil Ind,Shielded(SHLD),4.7uH@100KHz,+/-20%,5.5A,40mOhm,SMD,7.3*6.6*3.0,G | CYNTEC CO. LTD | PCMC063T-4R7MN |  | G |  |  |  |  |  |  |  |
|  |  |  |  |  | 244 | 63031AD04-129-G |  | IND,4.7uH@100KHz,+/-20%,5.5A,40mOhm,SHLD,G,SMD | MAG.LAYERS, SCIENTIFIC-TECHNICS (KUNSHAN) CO., LTD. | SPS-06CZ-4R7M-V1 |  | G |  |  |  |  |  |  |  |
| Multi | ND | ND | Y(4) | 245 | 245 | 61011R400-017-G |  | RES,34.8KOhm,+/-1%,1/16W,G,SMD0402 | KOA SPEER ELECTRONICS, INC. | RK73H1ETTP3482F | 1 | G | PFRR1 |  |  |  |  |  |  |
|  |  |  |  |  | 245 | 61011R400-012-G |  | RES,34.8KOhm,+/-1%,1/16W,G,SMD0402 | WALSIN TECHNOLOGY CORPORATION | WR04X3482FTL |  | G |  |  |  |  |  |  |  |
|  |  |  |  |  | 245 | 61011R400-011-G |  | RES,34.8KOhm,+/-1%,1/16W,G,SMD0402 | YAGEO CORPORATION COMPONENT | RC0402FR-0734K8L |  | G |  |  |  |  |  |  |  |
|  |  |  |  |  | 245 | 61011R400-044-G |  | RES,34.8KOhm,+/-1%,1/16W,G,SMD0402 | TA-I TECHNOLOGY CO., LTD | RM04FTN3482 |  | G |  |  |  |  |  |  |  |
| Multi | N |  | N | 246 | 246 | 61100YB00-017-G |  | RES,2.94KOhm,+/-0.1%,1/16W,G,SMD0402 | KOA SPEER ELECTRONICS, INC. | RN731ETTP2941B25 | 1 | G | PFRR19 |  |  |  |  |  |  |
|  |  |  |  |  | 246 | 61100YB00-011-G |  | RES,2.94KOhm,+/-0.1%,1/16W,G,SMD0402 | YAGEO CORPORATION COMPONENT | RT0402BRD072K94L |  | G |  |  |  |  |  |  |  |
|  |  |  |  |  | 246 | 61100YB00-044-G |  | RES,2.94KOhm,+/-0.1%,1/16W,G,SMD0402 | TA-I TECHNOLOGY CO., LTD | RB04BTP2941 |  | G |  |  |  |  |  |  |  |
| Multi | ND | ND | Y(3) | 247 | 247 | 62011DB01-015-G | - | CAP,1nF,+/-10%,X7R,100V,G,SMD0402 | MURATA ELEC. NORTH AMERICA | GRM155R72A102KA01D | 1 | G | PHAC3 |  |  |  |  |  |  |
|  |  |  |  |  | 247 | 62011DB00-011-G |  | CAP,1nF,+/-10%,X7R,100V,G,SMD0402 | YAGEO CORPORATION COMPONENT | CC0402KRX7R0BB102 |  | G |  |  |  |  |  |  |  |
| Multi | ND |  | Y(1) | 248 | 248 | 620135500-015-G |  | CAP,39nF,+/-10%,X7R,100V,G,SMD0805 | MURATA ELEC. NORTH AMERICA | GRM21BR72A393KA01L | 1 | G | PHAC18 |  |  |  |  |  |  |
|  |  |  |  |  | 248 | 620135500-012-G |  | CAP,39nF,+/-10%,X7R,100V,G,SMD0805 | WALSIN TECHNOLOGY CORPORATION | 0805B393K101CT |  | G |  |  |  |  |  |  |  |
| Multi | ND |  | ND | 249 | 249 | 52170KE00-086-G |  | TVS Diode,SMCJ64A,G,DO-214AB-2,SMD | LITTELFUSE FAR EAST PTE LTD | SMCJ64A | 1 | G | PHAD1 |  |  |  |  |  |  |
|  |  |  |  |  | 249 | 52170ER00-237-G |  | TVS Diode,SMCJ64A-13-F,SMC/DO-214AB,2P,G | DIODES INCORPORATION | SMCJ64A-13-F |  | G |  |  |  |  |  |  |  |
| Single | N |  | N | 250 | 250 | 52030YE00-223-G |  | DIODE,Schottky,MBR5H100MFST1G,100V,5A,G,SO8FL-8,SMD | ON SEMICONDUCTOR CORP | MBR5H100MFST1G | 1 | G | PHAD2 |  |  |  |  |  |  |
| Multi | Y | ND | N | 251 | 251 | 52040EC00-237-G |  | DIODE,Zener,MMSZ5246B-7-F,16V,7.8mA,G,SOD123-2,SMD | DIODES INEORPORATION | MMSZ5246B-7-F | 1 | G | PHAD3 |  |  |  |  |  |  |
|  |  |  |  |  | 251 | 52040B500-223-G |  | DIODE,Zener,MMSZ5246BT1G,16V,7.8mA,G,SOD123-2,SMD | ON SEMICONDUCTOR CORP | MMSZ5246BT1G |  | G |  |  |  |  |  |  |  |
|  |  |  |  |  | 251 | 52040EY00-031-G |  | Diode,ZENER,BZT52H-C16,17.1V,5mA,G,SOD123F-2,SMD | NXP SEMICONDUCTORS | BZT52H-C16 |  | G |  |  |  |  |  |  |  |
| Multi | N |  | N | 252 | 252 | 51031VY00-031-G |  | MOS N,PSMN4R8-100BSE,100V,120A,4.8m@10V,G,SOT404-3,SMD | NXP SEMICONDUCTORS | PSMN4R8-100BSE | 3 | G | PHAQ1,PHAQ2,PHAQ3 |  |  |  |  |  |  |
|  |  |  |  |  | 252 | 51032HE00-185-G |  | MOS N,FDB047N10,100V,120A,3.9m@10V,G,TO263-3,SMD | FAIRCHILD SEMICONDUCTOR CORP | FDB047N10 |  | G |  |  |  |  |  |  |  |
|  |  |  |  |  | 252 | 51032JY00-029-G |  | MOS N,SUM70040E-GE3,100V,120A,G,TO-263-3,SMD | VISHAY ENTER TECHNO LOGY.INC | SUM70040E-GE3 |  | G |  |  |  |  |  |  |  |
| Multi | ND |  | N | 253 | 253 | 51020A000-031-G |  | TRANS P,PBHV9115T,150V,1A,G,SOT23-3,SMD | NXP SEMICONDUCTORS | PBHV9115T | 1 | G | PHAQ4 |  |  |  |  |  |  |
|  |  |  |  |  | 253 | 51020BJ00-185-G |  | Trans PNP,MMBT5401,-150V,-600mA,G,SOT-23-3,SMD | FAIRCHILD SEMICONDUCTOR CORP | MMBT5401 |  | G |  |  |  |  |  |  |  |
|  |  |  |  |  | 253 | 510204N00-237-G |  | Trans PNP,MMBT5401-7-F,-150V,-600mA,SOT-23,3P,G | DIODES INCORPORATION | MMBT5401-7-F |  | G |  |  |  |  |  |  |  |
| Single | N |  | N | 254 | 254 | 51032D100-237-G |  | MOS N,DMN10H220L-7,100V,1.6A,220m@10V,G,SOT-23-3,SMD | DIODES INCORPORATION | DMN10H220L-7 | 2 | G | PHAQ5,PHAQ6 |  |  |  |  |  |  |
| Single | ND |  | ND | 255 | 255 | 610601801-32D-G |  | RES,0.5mOhm,+/-1%,2W,G,SMD1225 | Thin Film Technology Corporation | CPA1225R0M50FW-T5 | 1 | G | PHAR1 |  |  |  |  |  |  |
| Multi | ND |  | Y(5) | 256 | 256 | 61100DA00-017-G |  | RES,33KOhm,+/-0.1%,1/16W,G,SMD0402 | KOA SPEER ELECTRONICS, INC. | RN731ETTP3302B25 | 1 | G | PHAR2 |  |  |  |  |  |  |
|  |  |  |  |  | 256 | 61100DA00-011-G |  | RES,33KOhm,+/-0.1%,1/16W,G,SMD0402 | YAGEO CORPORATION COMPONENT | RT0402BRD0733KL |  | G |  |  |  |  |  |  |  |
|  |  |  |  |  | 256 | 61100DA00-012-G |  | RES,33KOhm,+/-0.1%,1/16W,G,SMD0402 | WALSIN TECHNOLOGY CORPORATION | WF04U3302BTL |  | G |  |  |  |  |  |  |  |
| Multi | ND |  | Y(5) | 257 | 257 | 61100QM00-017-G |  | RES,100KOhm,+/-0.1%,1/10W,G,SMD0603 | KOA SPEER ELECTRONICS, INC. | RN73H1JTTD1003B25 | 1 | G | PHAR5 |  |  |  |  |  |  |
|  |  |  |  |  | 257 | 61100QM00-012-G |  | RES,100KOhm,+/-0.1%,1/10W,G,SMD0603 | WALSIN TECHNOLOGY CORPORATION | WF06Q1003BTL |  | G |  |  |  |  |  |  |  |
|  |  |  |  |  | 257 | 61100QM00-011-G |  | RES,100KOhm,+/-0.1%,1/10W,G,SMD0603 | YAGEO CORPORATION COMPONENT | RT0603BRD07100KL |  | G |  |  |  |  |  |  |  |
| Multi | ND | ND | Y(4) | 258 | 258 | 610100R00-017-G | - | RES,3.74KOhm,+/-1%,1/10W,G,SMD0603 | KOA SPEER ELECTRONICS, INC. | RK73H1JTTD3741F | 1 | G | PHAR6 |  |  |  |  |  |  |
|  |  |  |  |  | 258 | 610100R00-012-G |  | RES,3.74KOhm,+/-1%,1/10W,G,SMD0603 | WALSIN TECHNOLOGY CORPORATION | WR06X3741FTL |  | G |  |  |  |  |  |  |  |
|  |  |  |  |  | 258 | 610100R00-011-G |  | RES,3.74KOhm,+/-1%,1/10W,G,SMD0603 | YAGEO CORPORATION COMPONENT | RC0603FR-073K74L |  | G |  |  |  |  |  |  |  |
|  |  |  |  |  | 258 | 610100R00-044-G |  | RES,3.74KOhm,+/-1%,1/10W,G,SMD0603 | TA-I TECHNOLOGY CO., LTD | RM06FTN3741 |  | G |  |  |  |  |  |  |  |
| Multi | N | Other | Y(4) | 259 | 259 | 610107P00-017-G |  | RES,4.12KOhm,+/-1%,1/10W,G,SMD0603 | KOA SPEER ELECTRONICS, INC. | RK73H1JTTD4121F | 1 | G | PHAR7 |  |  |  |  |  |  |
|  |  |  |  |  | 259 | 610107P00-012-G |  | RES,4.12KOhm,+/-1%,1/10W,G,SMD0603 | WALSIN TECHNOLOGY CORPORATION | WR06X4121FTL |  | G |  |  |  |  |  |  |  |
|  |  |  |  |  | 259 | 610107P00-011-G |  | RES,4.12KOhm,+/-1%,1/10W,G,SMD0603 | YAGEO CORPORATION COMPONENT | RC0603FR-074K12L |  | G |  |  |  |  |  |  |  |
|  |  |  |  |  | 259 | 610107P00-044-G |  | RES,4.12KOhm,+/-1%,1/10W,G,SMD0603 | TA-I TECHNOLOGY CO., LTD | RM06FTN4121 |  | G |  |  |  |  |  |  |  |
| Multi | ND |  | Y(4) | 260 | 260 | 61013GW00-017-G |  | RES,150KOhm,+/-1%,1/8W,G,SMD0805 | KOA SPEER ELECTRONICS, INC. | RK73H2ATTD1503F | 1 | G | PHAR13 |  |  |  |  |  |  |
|  |  |  |  |  | 260 | 61013GW00-012-G |  | RES,150KOhm,+/-1%,1/8W,G,SMD0805 | WALSIN TECHNOLOGY CORPORATION | WR08X1503FTL |  | G |  |  |  |  |  |  |  |
|  |  |  |  |  | 260 | 61013GW00-011-G |  | RES,150KOhm,+/-1%,1/8W,G,SMD0805 | YAGEO CORPORATION COMPONENT | RC0805FR-07150KL |  | G |  |  |  |  |  |  |  |
|  |  |  |  |  | 260 | 61013GW00-044-G |  | RES,150KOhm,+/-1%,1/8W,G,SMD0805 | TA-I TECHNOLOGY CO., LTD | RM10FTN1503 |  | G |  |  |  |  |  |  |  |
| Multi | N | ND | Y(4) | 261 | 261 | 610119P00-017-G | - | RES,5.11KOhm,+/-1%,1/16W,G,SMD0402 | KOA SPEER ELECTRONICS, INC. | RK73H1ETTP5111F | 1 | G | PHAR20 |  |  |  |  |  |  |
|  |  |  |  |  | 261 | 610119P00-012-G |  | RES,5.11KOhm,+/-1%,1/16W,G,SMD0402 | WALSIN TECHNOLOGY CORPORATION | WR04X5111FTL |  | G |  |  |  |  |  |  |  |
|  |  |  |  |  | 261 | 610119P00-011-G |  | RES,5.11KOhm,+/-1%,1/16W,G,SMD0402 | YAGEO CORPORATION COMPONENT | RC0402FR-075K11L |  | G |  |  |  |  |  |  |  |
|  |  |  |  |  | 261 | 610119P00-024-G |  | RES,5.11KOhm,+/-1%,1/16W,G,SMD0402 | PANASONIC INDUSTRIAL CO.,LTD. | ERJ2RKF5111X |  | G |  |  |  |  |  |  |  |
|  |  |  |  |  | 261 | 610119P00-029-G |  | RES,5.11KOhm,+/-1%,1/16W,G,SMD0402 | VISHAY ENTER TECHNO LOGY.INC | CRCW04025K11FKED |  | G |  |  |  |  |  |  |  |
| Multi | ND | ND | Y(4) | 262 | 262 | 610113D00-017-G | - | RES,10.5KOhm,+/-1%,1/16W,G,SMD0402 | KOA SPEER ELECTRONICS, INC. | RK73H1ETTP1052F | 1 | G | PHAR35 |  |  |  |  |  |  |
|  |  |  |  |  | 262 | 610113D00-011-G |  | RES,10.5KOhm,+/-1%,1/16W,G,SMD0402 | YAGEO CORPORATION COMPONENT | RC0402FR-0710K5L |  | G |  |  |  |  |  |  |  |
|  |  |  |  |  | 262 | 610113D00-012-G |  | RES,10.5KOhm,+/-1%,1/16W,G,SMD0402 | WALSIN TECHNOLOGY CORPORATION | WR04X1052FTL |  | G |  |  |  |  |  |  |  |
|  |  |  |  |  | 262 | 610113D00-044-G |  | RES,10.5KOhm,+/-1%,1/16W,G,SMD0402 | TA-I TECHNOLOGY CO., LTD | RM04FTN1052 |  | G |  |  |  |  |  |  |  |
| Multi | ND | ND | Y(4) | 263 | 263 | 61012Y700-017-G |  | RES,49.9KOhm,+/-1%,1/8W,G,SMD0805 | KOA SPEER ELECTRONICS, INC. | RK73H2ATTD4992F | 1 | G | PHAR78 |  |  |  |  |  |  |
|  |  |  |  |  | 263 | 61012Y700-012-G |  | RES,49.9KOhm,+/-1%,1/8W,G,SMD0805 | WALSIN TECHNOLOGY CORPORATION | WR08X4992FTL |  | G |  |  |  |  |  |  |  |
|  |  |  |  |  | 263 | 61012Y700-011-G |  | RES,49.9KOhm,+/-1%,1/8W,G,SMD0805 | YAGEO CORPORATION COMPONENT | RC0805FR-0749K9L |  | G |  |  |  |  |  |  |  |
|  |  |  |  |  | 263 | 61012Y700-044-G |  | RES,49.9KOhm,+/-1%,1/8W,G,SMD0805 | TA-I TECHNOLOGY CO., LTD | RM10FTN4992 |  | G |  |  |  |  |  |  |  |
| Single | ND |  | Y(1) | 264 | 264 | 32023RR00-183-G |  | IC,Power Controller,LM5066IPMHX/NOPB,G,HTSSOP-28,SMD | TEXAS INSTRUMENTS | LM5066IPMHX/NOPB | 1 | G | PHAU1 |  |  |  |  |  |  |
| Multi | N |  | Y(5) | 265 | 265 | 611006C00-017-G |  | RES,4.12KOhm,+/-0.1%,1/16W,G,SMD0402 | KOA SPEER ELECTRONICS, INC. | RN731ETTP4121B25 | 3 | G | PSIR13,PSIR15,PQPR19 |  |  |  |  |  |  |
|  |  |  |  |  | 265 | 611006C00-024-G |  | RES,4.12KOhm,+/-0.1%,1/16W,G,SMD0402 | PANASONIC INDUSTRIAL CO.,LTD. | ERA2AEB4121X |  | G |  |  |  |  |  |  |  |
|  |  |  |  |  | 265 | 611006C00-029-G |  | RES,4.12KOhm,+/-0.1%,1/16W,G,SMD0402 | VISHAY ENTER TECHNO LOGY.INC | TNPW04024K12BEED |  | G |  |  |  |  |  |  |  |
| Multi | ND |  | N | 266 | 266 | 630328U00-088-G |  | IND,3.3uH@100KHz,+/-20%,6A,30mOhm,SHLD,G,SMD | COOPER BUSSMANN, INC. | HCM0703-3R3-R | 3 | G | PSTL2,PSLL2,PSDL2 |  |  |  |  |  |  |
|  |  |  |  |  | 266 | 63034QP00-034-G |  | IND,3.3uH@100KHz,+/-20%,6.5A,21mOhm,SHLD,G,SMD | CYNTEC CO. LTD | PCME063T-3R3MS |  | G |  |  |  |  |  |  |  |
| Multi | N |  | Y(5) | 267 | 267 | 61100KM01-017-G |  | RES,15KOhm,+/-0.1%,1/16W,G,SMD0402 | KOA SPEER ELECTRONICS, INC. | RN73H1ETTP1502B25 | 1 | G | PSDR19 |  |  |  |  |  |  |
|  |  |  |  |  | 267 | 61100KM02-024-G |  | RES,15KOhm,+/-0.1%,1/16W,G,SMD0402 | PANASONIC INDUSTRIAL CO.,LTD. | ERA2AEB153X |  | G |  |  |  |  |  |  |  |
| Multi | ND |  | N | 268 | 268 | 63032A900-088-G |  | IND,1.5uH@100KHz,+/-20%,9A,15mOhm,SHLD,G,SMD | COOPER BUSSMANN, INC. | HCM0703-1R5-R | 2 | G | PSIL1,PSEL2 |  |  |  |  |  |  |
|  |  |  |  |  | 268 | 63032BW00-034-G |  | IND,1.5uH@100KHz,+/-20%,9A,15mOhm,SHLD,G,SMD | CYNTEC CO. LTD | PCMC063T-1R5MN |  | G |  |  |  |  |  |  |  |
|  |  |  |  |  | 268 | 63030HW00-051-G |  | IND,1.5uH@100KHz,+/-20%,9A,11.8mOhm,SHLD,G,SMD | PULSE ELECTRONICS (SINGAPORE) | PG0426.152NLT |  | G |  |  |  |  |  |  |  |
| Multi | ND |  | Y(5) | 269 | 269 | 61100V400-017-G |  | RES,13.7KOhm,+/-0.1%,1/16W,G,SMD0402 | KOA SPEER ELECTRONICS, INC. | RN731ETTP1372B25 | 1 | G | PSER19 |  |  |  |  |  |  |
|  |  |  |  |  | 269 | 61100V400-024-G |  | RES,13.7KOhm,+/-0.1%,1/16W,G,SMD0402 | PANASONIC INDUSTRIAL CO.,LTD. | ERA2AEB1372X |  | G |  |  |  |  |  |  |  |
|  |  |  |  |  | 269 | 61100V400-029-G |  | RES,13.7KOhm,+/-0.1%,1/16W,G,SMD0402 | VISHAY ENTER TECHNO LOGY.INC | TNPW040213K7BEED |  | G |  |  |  |  |  |  |  |
| Multi | ND |  | Y | 270 | 270 | 61100Y900-017-G |  | RES,11.8KOhm,+/-0.1%,1/16W,G,SMD0402 | KOA SPEER ELECTRONICS, INC. | RN731ETTP1182B25 | 1 | G | PSFR19 |  |  |  |  |  |  |
|  |  |  |  |  | 270 | 61100Y900-024-G |  | RES,11.8KOhm,+/-0.1%,1/16W,G,SMD0402 | PANASONIC INDUSTRIAL CO.,LTD. | ERA2AEB1182X |  | G |  |  |  |  |  |  |  |
|  |  |  |  |  | 270 | 61100Y900-029-G |  | RES,11.8KOhm,+/-0.1%,1/16W,G,SMD0402 | VISHAY ENTER TECHNO LOGY.INC | TNPW040211K8BEED |  | G |  |  |  |  |  |  |  |
| Multi | N | ND | Y(3) | 271 | 271 | 62011LY01-015-G | - | CAP,160pF,+/-5%,NPO(C0G),50V,G,SMD0402 | MURATA ELEC. NORTH AMERICA | GRM1555C1H161JA01D | 1 | G | PSIC3 |  |  |  |  |  |  |
|  |  |  |  |  | 271 | 62011LY00-012-G |  | CAP,MLCC,160pF,+/-5%,NPO(C0G),50V,SMD0402,G | WALSIN TECHNOLOGY CORPORATION | 0402N161J500LT |  | G |  |  |  |  |  |  |  |
|  |  |  |  |  | 271 | 62011LY00-011-G |  | CAP,MLCC,160pF,+/-5%,NPO(C0G),50V,SMD0402,G | YAGEO CORPORATION COMPONENT | CC0402JRNPO9BN161 |  | G |  |  |  |  |  |  |  |
| Multi | ND | ND | Y(4) | 272 | 272 | 61011MA00-017-G | - | RES,3.32KOhm,+/-1%,1/16W,G,SMD0402 | KOA SPEER ELECTRONICS, INC. | RK73H1ETTP3321F | 1 | G | PSIR2 |  |  |  |  |  |  |
|  |  |  |  |  | 272 | 61011MA00-012-G |  | RES,3.32KOhm,+/-1%,1/16W,G,SMD0402 | WALSIN TECHNOLOGY CORPORATION | WR04X3321FTL |  | G |  |  |  |  |  |  |  |
|  |  |  |  |  | 272 | 61011MA00-011-G |  | RES,3.32KOhm,+/-1%,1/16W,G,SMD0402 | YAGEO CORPORATION COMPONENT | RC0402FR-073K32L |  | G |  |  |  |  |  |  |  |
|  |  |  |  |  | 272 | 61011MA00-044-G |  | RES,3.32KOhm,+/-1%,1/16W,G,SMD0402 | TA-I TECHNOLOGY CO., LTD | RM04FTN3321 |  | G |  |  |  |  |  |  |  |
| Multi | ND |  | Y(5) | 273 | 273 | 61100DF00-017-G |  | RES,6.34KOhm,+/-0.1%,1/16W,G,SMD0402 | KOA SPEER ELECTRONICS, INC. | RN731ETTP6341B25 | 1 | G | PSLR19 |  |  |  |  |  |  |
|  |  |  |  |  | 273 | 61100DF00-011-G |  | RES,6.34KOhm,+/-0.1%,1/16W,G,SMD0402 | YAGEO CORPORATION COMPONENT | RT0402BRD076K34L |  | G |  |  |  |  |  |  |  |
|  |  |  |  |  | 273 | 61100DF00-044-G |  | RES,6.34KOhm,+/-0.1%,1/16W,G,SMD0402 | TA-I TECHNOLOGY CO., LTD | RB04BTP6341 |  | G |  |  |  |  |  |  |  |
|  |  |  |  |  | 273 | 61100DF00-024-G |  | RES,6.34KOhm,+/-0.1%,1/16W,G,SMD0402 | PANASONIC INDUSTRIAL CO.,LTD. | ERA2AEB6341X |  | G |  |  |  |  |  |  |  |
|  |  |  |  |  | 273 | 61100DF00-029-G |  | RES,6.34KOhm,+/-0.1%,1/16W,G,SMD0402 | VISHAY ENTER TECHNO LOGY.INC | TNPW04026K34BEED |  | G |  |  |  |  |  |  |  |
|  |  |  |  |  | 273 | 61100DF00-012-G |  | RES,6.34KOhm,+/-0.1%,1/16W,G,SMD0402 | WALSIN TECHNOLOGY CORPORATION | WF04U6341BTL |  | G |  |  |  |  |  |  |  |
| Multi | N |  | N | 274 | 274 | 62013BS00-015-G |  | CAP,3nF,+/-10%,X7R,50V,G,SMD0402 | MURATA ELEC. NORTH AMERICA | GRM155R71H302KA01D | 1 | G | PSPC10 |  |  |  |  |  |  |
|  |  |  |  |  | 274 | 62013BS00-012-G |  | CAP,3nF,+/-10%,X7R,50V,G,SMD0402 | WALSIN TECHNOLOGY CORPORATION | 0402B302K500CT |  | G |  |  |  |  |  |  |  |
| Multi | ND | ND | N | 275 | 275 | 62120BA00-022-G |  | SPEA,CAP,180uF,+/-20%,16V,105C,G,SMD6.3*5.9,ESR<=22mOhm | SANYO ELECTRIC CO., LTD. | 16SVPF180M | 1 | G | PSRCE1 |  |  |  |  |  |  |
|  |  |  |  |  | 275 | 62120D701-021-G |  | SPEA CAP,180uF,+/-20%,16V,105_x0003_,G,SMD6.3*5.8,ESR<=22mOhm | NIPPON CHEMI-CON CORPORATION | APXG160ARA181MF61G |  | G |  |  |  |  |  |  |  |
| Single | ND |  | Y(1) | 276 | 276 | 62012T500-015-G |  | CAP,22uF,+/-20%,X7S,25V,G,SMD1206 | MURATA ELEC. NORTH AMERICA | GRM31CC71E226ME11L | 12 | G | PSRC4,PSUC5,PSRC5,PSUC6,PSRC6,PSUC7,PSUC8,PSUC9,PSUC10,PSRC3001,PSRC3002,PSRC3005 |  |  |  |  |  |  |
| Single | N |  | N | 277 | 277 | 62013BQ00-015-G |  | CAP,3.6nF,+/-10%,X7R,50V,G,SMD0402 | MURATA ELEC. NORTH AMERICA | GRM155R71H362KA01D | 1 | G | PSRC7 |  |  |  |  |  |  |
| Multi | ND | ND | N | 278 | 278 | 63033PG00-15A-G | - | IND,22nH@100KHz,+/-15%,22A,249.55uOhm,SHLD,G,SMD | The Inter-Technical Group, Inc. | SLC1615A-R022LHF | 1 | G | PSRL1 |  |  |  |  |  |  |
|  |  |  |  |  | 278 | 63035Y500-129-G |  | IND,22nH@100KHz,+/-15%,22A,249.55uOhm,SHLD,G,SMD | MAG.LAYERS, SCIENTIFIC-TECHNICS (KUNSHAN) CO., LTD. | MSI-400404-22NL-I |  | G |  |  |  |  |  |  |  |
|  |  |  |  |  | 278 | 63035SH00-065-G |  | IND,22nH@100KHz,+/-15%,22A,249.55uOhm,SHLD,G,SMD | DELTA ELECTRONICS INDUSTRIAL CO.,LTD | HCB0439-220 |  | G |  |  |  |  |  |  |  |
| Multi | ND |  | N | 279 | 279 | 63034GW00-088-G |  | IND,680nH@100KHz,+/-20%,34A,1.33mOhm,SHLD,G,SMD | COOPER BUSSMANN, INC. | HCM1305-R68-R | 1 | G | PSRL2 |  |  |  |  |  |  |
|  |  |  |  |  | 279 | 630365H00-034-G |  | IND,680nH@100KHz,+/-20%,29.5A,1.55mOhm,SHLD,G,SMD | CYNTEC CO. LTD | CMLB135T-R68MS |  | G |  |  |  |  |  |  |  |
| Multi | ND | ND | Y(4) | 280 | 280 | 61011MN00-017-G |  | RES,976 Ohm,+/-1%,1/16W,G,SMD0402 | KOA SPEER ELECTRONICS, INC. | RK73H1ETTP9760F | 1 | G | PSRR11 |  |  |  |  |  |  |
|  |  |  |  |  | 280 | 61011MN00-012-G |  | RES,976 Ohm,+/-1%,1/16W,G,SMD0402 | WALSIN TECHNOLOGY CORPORATION | WR04X9760FTL |  | G |  |  |  |  |  |  |  |
|  |  |  |  |  | 280 | 61011MN00-011-G |  | RES,976 Ohm,+/-1%,1/16W,G,SMD0402 | YAGEO CORPORATION COMPONENT | RC0402FR-07976RL |  | G |  |  |  |  |  |  |  |
| Multi | ND |  | Y(5) | 281 | 281 | 61100P800-017-G |  | RES,8.45KOhm,+/-0.1%,1/16W,G,SMD0402 | KOA SPEER ELECTRONICS, INC. | RN731ETTP8451B25 | 1 | G | PSRR12 |  |  |  |  |  |  |
|  |  |  |  |  | 281 | 61100P800-024-G |  | RES,8.45KOhm,+/-0.1%,1/16W,G,SMD0402 | PANASONIC INDUSTRIAL CO.,LTD. | ERA2AEB8451X |  | G |  |  |  |  |  |  |  |
|  |  |  |  |  | 281 | 61100P800-029-G |  | RES,8.45KOhm,+/-0.1%,1/16W,G,SMD0402 | VISHAY ENTER TECHNO LOGY.INC | TNPW04028K45BEED |  | G |  |  |  |  |  |  |  |
| Multi | N | ND | Y(4) | 282 | 282 | 610114A00-017-G |  | RES,24.9KOhm,+/-1%,1/16W,G,SMD0402 | KOA SPEER ELECTRONICS, INC. | RK73H1ETTP2492F | 1 | G | PSRR13 |  |  |  |  |  |  |
|  |  |  |  |  | 282 | 610114A00-012-G |  | RES,24.9KOhm,+/-1%,1/16W,G,SMD0402 | WALSIN TECHNOLOGY CORPORATION | WR04X2492FTL |  | G |  |  |  |  |  |  |  |
|  |  |  |  |  | 282 | 610114A00-011-G |  | RES,24.9KOhm,+/-1%,1/16W,G,SMD0402 | YAGEO CORPORATION COMPONENT | RC0402FR-0724K9L |  | G |  |  |  |  |  |  |  |
|  |  |  |  |  | 282 | 610114A00-024-G |  | RES,24.9KOhm,+/-1%,1/16W,G,SMD0402 | PANASONIC INDUSTRIAL CO.,LTD. | ERJ2RKF2492X |  | G |  |  |  |  |  |  |  |
|  |  |  |  |  | 282 | 610114A00-029-G |  | RES,24.9KOhm,+/-1%,1/16W,G,SMD0402 | VISHAY ENTER TECHNO LOGY.INC | CRCW040224K9FKED |  | G |  |  |  |  |  |  |  |
| Multi | ND |  | Y(5) | 283 | 283 | 61100PM00-017-G |  | RES,453 Ohm,+/-0.1%,1/16W,G,SMD0402 | KOA SPEER ELECTRONICS, INC. | RN731ETTP4530B25 | 1 | G | PSRR17 |  |  |  |  |  |  |
|  |  |  |  |  | 283 | 61100PM00-011-G |  | RES,453 Ohm,+/-0.1%,1/16W,G,SMD0402 | YAGEO CORPORATION COMPONENT | RT0402BRD07453RL |  | G |  |  |  |  |  |  |  |
|  |  |  |  |  | 283 | 61100PM00-044-G |  | RES,453 Ohm,+/-0.1%,1/16W,G,SMD0402 | TA-I TECHNOLOGY CO., LTD | RB04BTP4530 |  | G |  |  |  |  |  |  |  |
|  |  |  |  |  | 283 | 61100PM00-012-G |  | RES,453 Ohm,+/-0.1%,1/16W,G,SMD0402 | WALSIN TECHNOLOGY CORPORATION | WF04U4530BTL |  | G |  |  |  |  |  |  |  |
| Multi | ND |  | Y(4) | 284 | 284 | 61011C300-017-G |  | RES,2.2 Ohm,+/-1%,1/16W,G,SMD0402 | KOA SPEER ELECTRONICS, INC. | RK73H1ETTP2R20F | 1 | G | PSRR3006 |  |  |  |  |  |  |
|  |  |  |  |  | 284 | 61011C300-012-G |  | RES,2.2 Ohm,+/-1%,1/16W,G,SMD0402 | WALSIN TECHNOLOGY CORPORATION | WR04W2R20FTL |  | G |  |  |  |  |  |  |  |
|  |  |  |  |  | 284 | 61011C300-011-G |  | RES,2.2 Ohm,+/-1%,1/16W,G,SMD0402 | YAGEO CORPORATION COMPONENT | RC0402FR-072R2L |  | G |  |  |  |  |  |  |  |
|  |  |  |  |  | 284 | 61011C300-044-G |  | RES,2.2 Ohm,+/-1%,1/16W,G,SMD0402 | TA-I TECHNOLOGY CO., LTD | RM04FTN2R20 |  | G |  |  |  |  |  |  |  |
| Single | ND |  | N | 285 | 285 | 32013FK00-238-G |  | IC,Regulator,IR3846MTRPBF,ADJ,35A,G,PQFN-26,SMD | INTERNATIONAL RECTIFIER | IR3846MTRPBF | 1 | G | PSRU1 |  |  |  |  |  |  |
| Multi | N |  | Y(5) | 286 | 286 | 61100QA00-017-G |  | RES,16KOhm,+/-0.1%,1/16W,G,SMD0402 | KOA SPEER ELECTRONICS, INC. | RN731ETTP1602B25 | 1 | G | PSTR17 |  |  |  |  |  |  |
|  |  |  |  |  | 286 | 61100QA01-024-G |  | RES,16KOhm,+/-0.1%,1/16W,G,SMD0402 | PANASONIC INDUSTRIAL CO.,LTD. | ERA2AEB163X |  | G |  |  |  |  |  |  |  |
|  |  |  |  |  | 286 | 61100QA00-029-G |  | RES,16KOhm,+/-0.1%,1/16W,G,SMD0402 | VISHAY ENTER TECHNO LOGY.INC | TNPW040216K0BEED |  | G |  |  |  |  |  |  |  |
| Multi | N | ND | Y(5) | 287 | 287 | 61100J401-017-G |  | RES,1.78KOhm,+/-0.1%,1/16W,G,SMD0402 | KOA SPEER ELECTRONICS, INC. | RN73H1ETTP1781B25 | 1 | G | PSTR19 |  |  |  |  |  |  |
|  |  |  |  |  | 287 | 61100J400-024-G |  | RES,1.78KOhm,+/-0.1%,1/16W,G,SMD0402 | PANASONIC INDUSTRIAL CO.,LTD. | ERA2AEB1781X |  | G |  |  |  |  |  |  |  |
|  |  |  |  |  | 287 | 61100J400-029-G |  | RES,1.78KOhm,+/-0.1%,1/16W,G,SMD0402 | VISHAY ENTER TECHNO LOGY.INC | MCS0402MD1781BE000 |  | G |  |  |  |  |  |  |  |
| Multi | ND | ND | Y(3) | 288 | 288 | 510301N00-223-G |  | MOS N,2N7002LT1G,60V,0.115A,7.5ohm@5V,G,SOT23-3,SMD | ON SEMICONDUCTOR CORP | 2N7002LT1G | 6 | G | PSUQ1,Q2,Q3,Q4,Q6,Q15 |  |  |  |  |  |  |
|  |  |  |  |  | 288 | 51030CQ00-185-G |  | MOS N,2N7002,60V,115mA,7.5ohm@5V,G,SOT23-3,SMD | FAIRCHILD SEMICONDUCTOR CORP | 2N7002 |  | G |  |  |  |  |  |  |  |
| Multi | N |  | Y(4) | 289 | 289 | 610119C00-017-G |  | RES,130KOhm,+/-1%,1/16W,G,SMD0402 | KOA SPEER ELECTRONICS, INC. | RK73H1ETTP1303F | 1 | G | PSUR1 |  |  |  |  |  |  |
|  |  |  |  |  | 289 | 610119C00-011-G |  | RES,130KOhm,+/-1%,1/16W,G,SMD0402 | YAGEO CORPORATION COMPONENT | RC0402FR-07130KL |  | G |  |  |  |  |  |  |  |
|  |  |  |  |  | 289 | 610119C00-012-G |  | RES,130KOhm,+/-1%,1/16W,G,SMD0402 | WALSIN TECHNOLOGY CORPORATION | WR04X1303FTL |  | G |  |  |  |  |  |  |  |
|  |  |  |  |  | 289 | 610119C00-044-G |  | RES,130KOhm,+/-1%,1/16W,G,SMD0402 | TA-I TECHNOLOGY CO., LTD | RM04FTN1303 |  | G |  |  |  |  |  |  |  |
| Multi | N |  | N | 290 | 290 | 880302300-065-G |  | Converter,input 40V~60V,600W,G,Q54SJ12050NNDH,OVAL | DELTA ELECTRONICS INDUSTRIAL CO.,LTD | Q54SJ12050NNDH | 1 | G | PSUU1 |  |  |  |  |  |  |
|  |  |  |  |  | 290 | 880302100-065-G |  | Converter,input 40V~60V,600W,G,Q54SH12050NNDH | DELTA ELECTRONICS INDUSTRIAL CO.,LTD | Q54SH12050NNDH |  | G |  |  |  |  |  |  |  |
| Multi | ND | ND | Y(3) | 291 | 291 | 510507500-185-G |  | MOS N/P,FDC6327C,20V,2.7/1.9A,80m/170m@4.5V,G,SuperSOT-6,SMD | FAIRCHILD SEMICONDUCTOR CORP | FDC6327C | 1 | G | QN1 |  |  |  |  |  |  |
|  |  |  |  |  | 291 | 51050BG00-223-G |  | MOS N/P,NTGD4167CT1G,30V,2.9/2.2A,90m/170m@4.5V,G,TSOP-6,SMD | ON SEMICONDUCTOR CORP | NTGD4167CT1G |  | G |  |  |  |  |  |  |  |
|  |  |  |  |  | 291 | 51050LB00-237-G |  | MOS N/P,DMC2038LVT,+/-20V,4.5A/-3.1A,35m@4.5V,G,TSOT-6,SMD | DIODES INCORPORATION | DMC2038LVT |  | G |  |  |  |  |  |  |  |
| Multi | ND | ND | N | 292 | 292 | 510503B00-223-G |  | MOS N/N,NTZD3154NT1G,20V,0.54A,550m24.5V,G,SOT563-6,SMD | ON SEMICONDUCTOR CORP | NTZD3154NT1G | 2 | G | QN2,QN3 |  |  |  |  |  |  |
|  |  |  |  |  | 292 | 51050L500-029-G |  | MOS,N/N,Si1034CX-T1-GE3,20V,0.61A,G,SC-89-6,SMD | VISHAY ENTER TECHNO LOGY.INC | Si1034CX-T1-GE3 |  | G |  |  |  |  |  |  |  |
|  |  |  |  |  | 292 | 51050KW00-131-G |  | MOS N/N,SSM6N36FE,20V,500mA,0.63@5V,G,ES6-6,SMD | TOSHIBA ELECTRONICS ASIA LTD | SSM6N36FE |  | G |  |  |  |  |  |  |  |
| Multi | ND |  | N | 293 | 293 | 51030QP00-237-G |  | MOS N,BSS138W-7-F,50V,0.2A,3.5ohm@10V,G,SOT323-3,SMD | DIODES INEORPORATION | BSS138W-7-F | 44 | G | Q1,Q9,Q10,Q11,Q13,Q14,Q24,Q25,Q26,Q27,Q28,Q29,Q30,Q31,Q32,Q33,Q34,Q35,Q36,Q37,Q38,Q39,Q40,Q41,Q42,Q43,Q44,Q45,Q46,Q47,Q48,Q49,Q50,Q51,Q52,Q53,Q54,Q55,Q56,Q57,Q58,Q59,Q60,Q93 |  |  |  |  |  |  |
|  |  |  |  |  | 293 | 51031KA00-031-G |  | MOS N,BSS138PW,60V,320mA, 2ohm@5V,G,SC70-3,SMD | NXP SEMICONDUCTORS | BSS138PW |  | G |  |  |  |  |  |  |  |
|  |  |  |  |  | 293 | 51031WU00-221-G |  | MOS N,BSS138W H6327,60V,280mA,3.5m@10V,G,SOT323-3,SMD | INFINEON TECHNOLOGIES CORP. | BSS138W H6327 |  | G |  |  |  |  |  |  |  |
| Multi | ND |  | N | 294 | 294 | 510406000-185-G |  | MOS P,FDD6685,30V,11A,30m@4.5V,G,TO252-3,SMD | FAIRCHILD SEMICONDUCTOR CORP | FDD6685 | 2 | G | Q5,Q7 |  |  |  |  |  |  |
|  |  |  |  |  | 294 | 510410G00-221-G |  | MOS P,IPD042P03L3 G,-30V,-70A,TO-252-3,SMD | INFINEON TECHNOLOGIES CORP. | IPD042P03L3 G |  | G |  |  |  |  |  |  |  |
|  |  |  |  |  | 294 | 51040WQ00-131-G |  | MOSFET-P,TJ40S04M3L,-40V,-40A,9.1mOhm@Vgs=-10V,13mOhm@Vgs=-6V,SMD,3P,G | TOSHIBA ELECTRONICS ASIA LTD | TJ40S04M3L |  | G |  |  |  |  |  |  |  |
| Multi | ND | ND | N | 295 | 295 | 510501900-237-G | - | MOS N/N,2N7002DW-7-F,60V,0.115A,7.5ohm@5V,G,SOT363-6,SMD | DIODES INEORPORATION | 2N7002DW-7-F | 1 | G | Q12 |  |  |  |  |  |  |
|  |  |  |  |  | 295 | 51050HV00-031-G |  | FET Dual channel,NX7002BKS,60V,240mA,2.8Ohm@Vgs=10V,3.2Ohm@Vgs=5V,SOT-363,6P,G | NXP SEMICONDUCTORS | NX7002BKS |  | G |  |  |  |  |  |  |  |
|  |  |  |  |  | 295 | 510329S00-131-G |  | MOS N,SSM6N7002KFU,LF(T,60V,300mA,1.5@10V,G,US6-6,SMD | TOSHIBA ELECTRONICS ASIA LTD | SSM6N7002KFU,LF(T |  | G |  |  |  |  |  |  |  |
| Multi | N |  | Y(5) | 296 | 296 | 61100QE00-017-G |  | RES,240 Ohm,+/-0.1%,1/16W,G,SMD0402 | KOA SPEER ELECTRONICS, INC. | RN731ETTP2400B25 | 4 | G | R3,R8,R365,R370 |  |  |  |  |  |  |
|  |  |  |  |  | 296 | 61100QE00-011-G |  | RES,240 Ohm,+/-0.1%,1/16W,G,SMD0402 | YAGEO CORPORATION COMPONENT | RT0402BRD07240RL |  | G |  |  |  |  |  |  |  |
|  |  |  |  |  | 296 | 61100QE00-044-G |  | RES,240 Ohm,+/-0.1%,1/16W,G,SMD0402 | TA-I TECHNOLOGY CO., LTD | RB04BTP2400 |  | G |  |  |  |  |  |  |  |
|  |  |  |  |  | 296 | 61100QE00-012-G |  | RES,240 Ohm,+/-0.1%,1/16W,G,SMD0402 | WALSIN TECHNOLOGY CORPORATION | WF04U2400BTL |  | G |  |  |  |  |  |  |  |
| Multi | N | other | Y(4) | 297 | 297 | 610100T00-017-G |  | RES,1KOhm,+/-5%,1/16W,G,SMD0402 | KOA SPEER ELECTRONICS, INC. | RK73B1ETTP102J | 107 | G | R4,R5,R9,R10,R103,R129,R130,R131,R150,R151,R154,R171,R172,R175,R192,R193,R195,R213,R214,R215,R234,R235,R236,R255,R256,R259,R276,R277,R279,R318,R319,R366,R367,R371,R372,R455,R458,R484,R485,R486,R505,R506,R509,R526,R527,R530,R547,R548,R550,R568,R569,R570,R589,R590,R591,R611,R612,R615,R631,R632,R634,R704,R705,R706,R711,R715,R735,R736,R1072,R1080,R1232,R1340,R1341,R1350,R1351,R1352,R1353,R1354,R1355,R1356,R1357,R1358,R1359,R1361,R1363,R1364,R1365,R1366,R1367,R1377,R1378,R1379,R1380,R1381,R1382,R1383,R1384,R1385,R1386,R1387,R1388,R1389,R1390,R1391,R1392,R1746,R1775 |  |  |  |  |  |  |
|  |  |  |  |  | 297 | 610100T00-012-G |  | RES,1KOhm,+/-5%,1/16W,G,SMD0402 | WALSIN TECHNOLOGY CORPORATION | WR04X102JTL |  | G |  |  |  |  |  |  |  |
|  |  |  |  |  | 297 | 610100T00-011-G |  | RES,1KOhm,+/-5%,1/16W,G,SMD0402 | YAGEO CORPORATION COMPONENT | RC0402JR-071KL |  | G |  |  |  |  |  |  |  |
|  |  |  |  |  | 297 | 610100T00-044-G |  | RES,1KOhm,+/-5%,1/16W,G,SMD0402 | TA-I TECHNOLOGY CO., LTD | RM04JTN102 |  | G |  |  |  |  |  |  |  |
|  |  |  |  |  | 297 | 610100T00-024-G |  | RES,1KOhm,+/-5%,1/16W,G,SMD0402 | PANASONIC INDUSTRIAL CO.,LTD. | ERJ2GEJ102X |  | G |  |  |  |  |  |  |  |
| Single | ND | ND | Y(5) | 298 | 298 | 61100Y400-017-G | - | RES,169 Ohm,+/-0.1%,1/16W,G,SMD0402 | KOA SPEER ELECTRONICS, INC. | RN731ETTP1690B25 | 6 | G | R11,R12,R13,R373,R374,R375 |  |  |  |  |  |  |
| Multi | N | ND | Y(4) | 299 | 299 | 610102700-017-G | - | RES,49.9 Ohm,+/-1%,1/16W,G,SMD0402 | KOA SPEER ELECTRONICS, INC. | RK73H1ETTP49R9F | 208 | G | R16,R17,R18,R19,R20,R21,R24,R25,R33,R34,R35,R36,R37,R46,R47,R48,R49,R50,R51,R65,R66,R69,R76,R94,R95,R99,R100,R101,R104,R105,R106,R107,R110,R111,R112,R113,R114,R115,R117,R121,R122,R138,R139,R140,R146,R147,R148,R155,R160,R161,R164,R166,R169,R177,R180,R182,R186,R187,R189,R197,R198,R203,R206,R207,R208,R222,R223,R224,R230,R231,R232,R240,R244,R245,R248,R250,R253,R261,R264,R266,R270,R271,R273,R281,R282,R287,R291,R292,R293,R376,R379,R380,R381,R382,R383,R386,R387,R391,R392,R395,R396,R397,R398,R400,R405,R406,R407,R408,R409,R410,R421,R422,R423,R424,R425,R426,R427,R432,R435,R436,R445,R446,R449,R453,R456,R457,R459,R460,R461,R493,R494,R495,R501,R502,R503,R510,R515,R516,R519,R521,R524,R533,R535,R537,R541,R542,R544,R552,R553,R558,R561,R562,R563,R577,R578,R579,R585,R586,R587,R594,R599,R600,R603,R605,R608,R610,R617,R621,R625,R626,R628,R636,R637,R642,R645,R646,R647,R740,R748,R933,R935,R1346,R1348,R1349,R1368,R1371,R1374,R1396,R1397,R1401,R1402,R1408,R1409,R1410,R1411,R1419,R1420,R1421,R1429,R1430,R1431,R1591,R1822,R1827,R1828,R1829,R1830,R1831 |  |  |  |  |  |  |
|  |  |  |  |  | 299 | 610102700-012-G |  | RES,49.9 Ohm,+/-1%,1/16W,G,SMD0402 | WALSIN TECHNOLOGY CORPORATION | WR04X49R9FTL |  | G |  |  |  |  |  |  |  |
|  |  |  |  |  | 299 | 610102700-011-G |  | RES,49.9 Ohm,+/-1%,1/16W,G,SMD0402 | YAGEO CORPORATION COMPONENT | RC0402FR-0749R9L |  | G |  |  |  |  |  |  |  |
|  |  |  |  |  | 299 | 610102700-044-G |  | RES,49.9 Ohm,+/-1%,1/16W,G,SMD0402 | TA-I TECHNOLOGY CO., LTD | RM04FTN49R9 |  | G |  |  |  |  |  |  |  |
|  |  |  |  |  | 299 | 610102700-029-G |  | RES,49.9 Ohm,+/-1%,1/16W,G,SMD0402 | VISHAY ENTER TECHNO LOGY.INC | CRCW040249R9FKED |  | G |  |  |  |  |  |  |  |
|  |  |  |  |  | 299 | 610102700-024-G |  | RES,49.9 Ohm,+/-1%,1/16W,G,SMD0402 | PANASONIC INDUSTRIAL CO.,LTD. | ERJ2RKF49R9X |  | G |  |  |  |  |  |  |  |
| Multi |  |  | Y(4) | 300 | 300 | 61010KJ00-017-G |  | RES,3.3KOhm,+/-5%,1/16W,G,SMD0402 | KOA SPEER ELECTRONICS, INC. | RK73B1ETTP332J | 83 | G | R22,R23,R26,R32,R38,R39,R41,R42,R43,R44,R45,R52,R68,R88,R89,R299,R300,R301,R302,R342,R384,R385,R388,R389,R390,R394,R399,R401,R403,R404,R411,R412,R413,R441,R442,R465,R466,R468,R469,R470,R472,R475,R476,R954,R1029,R1031,R1032,R1033,R1034,R1035,R1041,R1042,R1043,R1044,R1047,R1048,R1050,R1051,R1054,R1055,R1059,R1060,R1063,R1064,R1067,R1068,R1127,R1128,R1139,R1141,R1225,R1227,R1229,R1234,R1239,R1336,R1337,R1466,R1468,R1524,R1525,R1553,R1823 |  |  |  |  |  |  |
|  |  |  |  |  | 300 | 61010KJ00-012-G |  | RES,3.3KOhm,+/-5%,1/16W,G,SMD0402 | WALSIN TECHNOLOGY CORPORATION | WR04X332JTL |  | G |  |  |  |  |  |  |  |
|  |  |  |  |  | 300 | 61010KJ00-011-G |  | RES,3.3KOhm,+/-5%,1/16W,G,SMD0402 | YAGEO CORPORATION COMPONENT | RC0402JR-073K3L |  | G |  |  |  |  |  |  |  |
|  |  |  |  |  | 300 | 61010KJ00-044-G |  | RES,3.3KOhm,+/-5%,1/16W,G,SMD0402 | TA-I TECHNOLOGY CO., LTD | RM04JTN332 |  | G |  |  |  |  |  |  |  |
|  |  |  |  |  | 300 | 61010KJ00-024-G |  | RES,3.3KOhm,+/-5%,1/16W,G,SMD0402 | PANASONIC INDUSTRIAL CO.,LTD. | ERJ2GEJ332X |  | G |  |  |  |  |  |  |  |
| Multi | ND | ND | Y(4) | 301 | 301 | 610115E00-017-G | - | RES,1.2KOhm,+/-5%,1/16W,G,SMD0402 | KOA SPEER ELECTRONICS, INC. | RK73B1ETTP122J | 12 | G | R27,R28,R54,R55,R56,R57,R58,R59,R417,R418,R419,R420 |  |  |  |  |  |  |
|  |  |  |  |  | 301 | 610115E00-012-G |  | RES,1.2KOhm,+/-5%,1/16W,G,SMD0402 | WALSIN TECHNOLOGY CORPORATION | WR04X122JTL |  | G |  |  |  |  |  |  |  |
|  |  |  |  |  | 301 | 610115E00-011-G |  | RES,1.2KOhm,+/-5%,1/16W,G,SMD0402 | YAGEO CORPORATION COMPONENT | RC0402JR-071K2L |  | G |  |  |  |  |  |  |  |
|  |  |  |  |  | 301 | 610115E00-044-G |  | RES,1.2KOhm,+/-5%,1/16W,G,SMD0402 | TA-I TECHNOLOGY CO., LTD | RM04JTN122 |  | G |  |  |  |  |  |  |  |
|  |  |  |  |  | 301 | 610115E00-024-G |  | RES,1.2KOhm,+/-5%,1/16W,G,SMD0402 | PANASONIC INDUSTRIAL CO.,LTD. | ERJ2GEJ122X |  | G |  |  |  |  |  |  |  |
| Multi | ND |  | Y(5) | 302 | 302 | 61100V600-017-G |  | RES,200 Ohm,+/-0.1%,1/16W,G,SMD0402 | KOA SPEER ELECTRONICS, INC. | RN731ETTP2000B25 | 6 | G | R31,R40,R53,R393,R402,R416 |  |  |  |  |  |  |
|  |  |  |  |  | 302 | 61100V600-011-G |  | RES,200 Ohm,+/-0.1%,1/16W,G,SMD0402 | YAGEO CORPORATION COMPONENT | RT0402BRD07200RL |  | G |  |  |  |  |  |  |  |
|  |  |  |  |  | 302 | 61100V600-044-G |  | RES,200 Ohm,+/-0.1%,1/16W,G,SMD0402 | TA-I TECHNOLOGY CO., LTD | RB04BTP2000 |  | G |  |  |  |  |  |  |  |
|  |  |  |  |  | 302 | 61100V600-012-G |  | RES,200 Ohm,+/-0.1%,1/16W,G,SMD0402 | WALSIN TECHNOLOGY CORPORATION | WF04U2000BTL |  | G |  |  |  |  |  |  |  |
| Multi | N | Other | Y(4) | 303 | 303 | 610115T00-017-G | - | RES,40.2KOhm,+/-1%,1/16W,G,SMD0402 | KOA SPEER ELECTRONICS, INC. | RK73H1ETTP4022F | 1 | G | R78 |  |  |  |  |  |  |
|  |  |  |  |  | 303 | 610115T00-012-G |  | RES,40.2KOhm,+/-1%,1/16W,G,SMD0402 | WALSIN TECHNOLOGY CORPORATION | WR04X4022FTL |  | G |  |  |  |  |  |  |  |
|  |  |  |  |  | 303 | 610115T00-011-G |  | RES,40.2KOhm,+/-1%,1/16W,G,SMD0402 | YAGEO CORPORATION COMPONENT | RC0402FR-0740K2L |  | G |  |  |  |  |  |  |  |
|  |  |  |  |  | 303 | 610115T00-044-G |  | RES,40.2KOhm,+/-1%,1/16W,G,SMD0402 | TA-I TECHNOLOGY CO., LTD | RM04FTN4022 |  | G |  |  |  |  |  |  |  |
|  |  |  |  |  | 303 | 610115T00-029-G |  | RES,40.2KOhm,+/-1%,1/16W,G,SMD0402 | VISHAY ENTER TECHNO LOGY.INC | CRCW040240K2FKEDC |  | G |  |  |  |  |  |  |  |
| Multi |  |  | Y(4) | 304 | 304 | 610112W00-017-G |  | RES,2KOhm,+/-5%,1/16W,G,SMD0402 | KOA SPEER ELECTRONICS, INC. | RK73B1ETTP202J | 5 | G | R97,R98,R447,R452,R454 |  |  |  |  |  |  |
|  |  |  |  |  | 304 | 610112W00-012-G |  | RES,2KOhm,+/-5%,1/16W,G,SMD0402 | WALSIN TECHNOLOGY CORPORATION | WR04X202JTL |  | G |  |  |  |  |  |  |  |
|  |  |  |  |  | 304 | 610112W00-011-G |  | RES,2KOhm,+/-5%,1/16W,G,SMD0402 | YAGEO CORPORATION COMPONENT | RC0402JR-072KL |  | G |  |  |  |  |  |  |  |
|  |  |  |  |  | 304 | 610112W00-044-G |  | RES,2KOhm,+/-5%,1/16W,G,SMD0402 | TA-I TECHNOLOGY CO., LTD | RM04JTN202 |  | G |  |  |  |  |  |  |  |
|  |  |  |  |  | 304 | 610112W00-024-G |  | RES,2KOhm,+/-5%,1/16W,G,SMD0402 | PANASONIC INDUSTRIAL CO.,LTD. | ERJ2GEJ202X |  | G |  |  |  |  |  |  |  |
| Multi | N | ND | Y(4) | 305 | 305 | 61010DL01-017-G | - | RES,0 Ohm,+/-5%,1/8W,G,SMD0805 | KOA SPEER ELECTRONICS, INC. | RK73Z2ATTD | 6 | G | R108,R109,R463,R464,R700,R701 |  |  |  |  |  |  |
|  |  |  |  |  | 305 | 61010DL00-012-G |  | RES,0 Ohm,+/-5%,1/8W,G,SMD0805 | WALSIN TECHNOLOGY CORPORATION | WR08X000PTL |  | G |  |  |  |  |  |  |  |
|  |  |  |  |  | 305 | 61010DL00-011-G |  | RES,0 Ohm,+/-5%,1/8W,G,SMD0805 | YAGEO CORPORATION COMPONENT | RC0805JR-070RL |  | G |  |  |  |  |  |  |  |
|  |  |  |  |  | 305 | 61010DL00-044-G |  | RES,0 Ohm,+/-5%,1/8W,G,SMD0805 | TA-I TECHNOLOGY CO., LTD | RM10JTN0 |  | G |  |  |  |  |  |  |  |
|  |  |  |  |  | 305 | 61010DL00-024-G |  | RES,0 Ohm,+/-5%,1/8W,G,SMD0805 | PANASONIC INDUSTRIAL CO.,LTD. | ERJ6GEY0R00V |  | G |  |  |  |  |  |  |  |
| Multi | ND | ND | Y(4) | 306 | 306 | 610102C00-017-G | - | RES,15KOhm,+/-5%,1/16W,G,SMD0402 | KOA SPEER ELECTRONICS, INC. | RK73B1ETTP153J | 18 | G | R123,R124,R125,R126,R127,R128,R327,R829,R835,R836,R1125,R1513,R1542,R1543,R1544,R1545,R1546,R1547 |  |  |  |  |  |  |
|  |  |  |  |  | 306 | 610102C00-011-G |  | RES,15KOhm,+/-5%,1/16W,G,SMD0402 | YAGEO CORPORATION COMPONENT | RC0402JR-0715KL |  | G |  |  |  |  |  |  |  |
|  |  |  |  |  | 306 | 610102C00-012-G |  | RES,15KOhm,+/-5%,1/16W,G,SMD0402 | WALSIN TECHNOLOGY CORPORATION | WR04X153JTL |  | G |  |  |  |  |  |  |  |
|  |  |  |  |  | 306 | 610102C00-044-G |  | RES,15KOhm,+/-5%,1/16W,G,SMD0402 | TA-I TECHNOLOGY CO., LTD | RM04JTN153 |  | G |  |  |  |  |  |  |  |
|  |  |  |  |  | 306 | 610102C00-024-G |  | RES,15KOhm,+/-5%,1/16W,G,SMD0402 | PANASONIC INDUSTRIAL CO.,LTD. | ERJ2GEJ153X |  | G |  |  |  |  |  |  |  |
|  |  |  |  |  | 306 | 610102C00-029-G |  | RES,15KOhm,+/-5%,1/16W,G,SMD0402 | VISHAY ENTER TECHNO LOGY.INC | CRCW040215K0JNED |  | G |  |  |  |  |  |  |  |
| Multi | N | other | Y(4) | 307 | 307 | 610102E00-017-G |  | RES,100 Ohm,+/-5%,1/16W,G,SMD0402 | KOA SPEER ELECTRONICS, INC. | RK73B1ETTP101J | 65 | G | R132,R137,R141,R143,R152,R158,R162,R167,R173,R179,R183,R188,R194,R200,R204,R209,R216,R221,R225,R227,R237,R239,R246,R251,R257,R263,R267,R272,R278,R284,R288,R290,R487,R492,R496,R498,R507,R513,R517,R522,R528,R531,R538,R543,R549,R555,R559,R564,R571,R576,R580,R582,R592,R597,R601,R606,R613,R620,R622,R627,R633,R639,R643,R648,R934 |  |  |  |  |  |  |
|  |  |  |  |  | 307 | 610102E00-012-G |  | RES,100 Ohm,+/-5%,1/16W,G,SMD0402 | WALSIN TECHNOLOGY CORPORATION | WR04X101JTL |  | G |  |  |  |  |  |  |  |
|  |  |  |  |  | 307 | 610102E00-011-G |  | RES,100 Ohm,+/-5%,1/16W,G,SMD0402 | YAGEO CORPORATION COMPONENT | RC0402JR-07100RL |  | G |  |  |  |  |  |  |  |
|  |  |  |  |  | 307 | 610102E00-044-G |  | RES,100 Ohm,+/-5%,1/16W,G,SMD0402 | TA-I TECHNOLOGY CO., LTD | RM04JTN101 |  | G |  |  |  |  |  |  |  |
|  |  |  |  |  | 307 | 610102E00-029-G |  | RES,100 Ohm,+/-5%,1/16W,G,SMD0402 | VISHAY ENTER TECHNO LOGY.INC | CRCW0402100RJNED |  | G |  |  |  |  |  |  |  |
| Multi | N | ND | Y(4) | 308 | 308 | 610107B00-017-G | K9576 | RES,4.7KOhm,+/-5%,1/16W,G,SMD0402 | KOA SPEER ELECTRONICS, INC. | RK73B1ETTP472J | 7 | G | R297,R298,R304,R1069,R1070,R1342,R1343 |  |  |  |  |  |  |
|  |  |  |  |  | 308 | 610107B00-012-G |  | RES,4.7KOhm,+/-5%,1/16W,G,SMD0402 | WALSIN TECHNOLOGY CORPORATION | WR04X472JTL |  | G |  |  |  |  |  |  |  |
|  |  |  |  |  | 308 | 610107B00-011-G |  | RES,4.7KOhm,+/-5%,1/16W,G,SMD0402 | YAGEO CORPORATION COMPONENT | RC0402JR-074K7L |  | G |  |  |  |  |  |  |  |
|  |  |  |  |  | 308 | 610107B00-044-G |  | RES,4.7KOhm,+/-5%,1/16W,G,SMD0402 | TA-I TECHNOLOGY CO., LTD | RM04JTN472 |  | G |  |  |  |  |  |  |  |
|  |  |  |  |  | 308 | 610107B00-024-G |  | RES,4.7KOhm,+/-5%,1/16W,G,SMD0402 | PANASONIC INDUSTRIAL CO.,LTD. | ERJ2GEJ472X |  | G |  |  |  |  |  |  |  |
|  |  |  |  |  | 308 | 610107B00-029-G |  | RES,4.7KOhm,+/-5%,1/16W,G,SMD0402 | VISHAY ENTER TECHNO LOGY.INC | CRCW04024K70JNED |  | G |  |  |  |  |  |  |  |
| Multi | ND | ND | Y(4) | 309 | 309 | 610112U00-017-G |  | RES,499 Ohm,+/-1%,1/16W,G,SMD0402 | KOA SPEER ELECTRONICS, INC. | RK73H1ETTP4990F | 1 | G | R307 |  |  |  |  |  |  |
|  |  |  |  |  | 309 | 610112U00-012-G |  | RES,499 Ohm,+/-1%,1/16W,G,SMD0402 | WALSIN TECHNOLOGY CORPORATION | WR04X4990FTL |  | G |  |  |  |  |  |  |  |
|  |  |  |  |  | 309 | 610112U00-011-G |  | RES,499 Ohm,+/-1%,1/16W,G,SMD0402 | YAGEO CORPORATION COMPONENT | RC0402FR-07499RL |  | G |  |  |  |  |  |  |  |
|  |  |  |  |  | 309 | 610112U00-044-G |  | RES,499 Ohm,+/-1%,1/16W,G,SMD0402 | TA-I TECHNOLOGY CO., LTD | RM04FTN4990 |  | G |  |  |  |  |  |  |  |
|  |  |  |  |  | 309 | 610112U00-024-G |  | RES,499 Ohm,+/-1%,1/16W,G,SMD0402 | PANASONIC INDUSTRIAL CO.,LTD. | ERJ2RKF4990X |  | G |  |  |  |  |  |  |  |
| Multi | N | other | Y(4) | 310 | 310 | 610107C00-017-G | K9577 | RES,10KOhm,+/-5%,1/16W,G,SMD0402 | KOA SPEER ELECTRONICS, INC. | RK73B1ETTP103J | 2 | G | R310,R990 |  |  |  |  |  |  |
|  |  |  |  |  | 310 | 610107C00-012-G |  | RES,10KOhm,+/-5%,1/16W,G,SMD0402 | WALSIN TECHNOLOGY CORPORATION | WR04X103JTL |  | G |  |  |  |  |  |  |  |
|  |  |  |  |  | 310 | 610107C00-011-G |  | RES,10KOhm,+/-5%,1/16W,G,SMD0402 | YAGEO CORPORATION COMPONENT | RC0402JR-0710KL |  | G |  |  |  |  |  |  |  |
|  |  |  |  |  | 310 | 610107C00-044-G |  | RES,10KOhm,+/-5%,1/16W,G,SMD0402 | TA-I TECHNOLOGY CO., LTD | RM04JTN103 |  | G |  |  |  |  |  |  |  |
|  |  |  |  |  | 310 | 610107C00-024-G |  | RES,10KOhm,+/-5%,1/16W,G,SMD0402 | PANASONIC INDUSTRIAL CO.,LTD. | ERJ2GEJ103X |  | G |  |  |  |  |  |  |  |
|  |  |  |  |  | 310 | 610107C00-029-G |  | RES,10KOhm,+/-5%,1/16W,G,SMD0402 | VISHAY ENTER TECHNO LOGY.INC | CRCW040210K0JNED |  | G |  |  |  |  |  |  |  |
| Multi | ND | ND | Y(4) | 311 | 311 | 61011MW00-017-G | - | RES,31.6KOhm,+/-1%,1/16W,G,SMD0402 | KOA SPEER ELECTRONICS, INC. | RK73H1ETTP3162F | 1 | G | R328 |  |  |  |  |  |  |
|  |  |  |  |  | 311 | 61011MW00-012-G |  | RES,31.6KOhm,+/-1%,1/16W,G,SMD0402 | WALSIN TECHNOLOGY CORPORATION | WR04X3162FTL |  | G |  |  |  |  |  |  |  |
|  |  |  |  |  | 311 | 61011MW00-011-G |  | RES,31.6KOhm,+/-1%,1/16W,G,SMD0402 | YAGEO CORPORATION COMPONENT | RC0402FR-0731K6L |  | G |  |  |  |  |  |  |  |
|  |  |  |  |  | 311 | 61011MW00-044-G |  | RES,31.6KOhm,+/-1%,1/16W,G,SMD0402 | TA-I TECHNOLOGY CO., LTD | RM04FTN3162 |  | G |  |  |  |  |  |  |  |
| Multi | ND | ND | Y(4) | 312 | 312 | 610118G00-017-G |  | RES,90.9KOhm,+/-1%,1/16W,G,SMD0402 | KOA SPEER ELECTRONICS, INC. | RK73H1ETTP9092F | 1 | G | R329 |  |  |  |  |  |  |
|  |  |  |  |  | 312 | 610118G00-012-G |  | RES,90.9KOhm,+/-1%,1/16W,G,SMD0402 | WALSIN TECHNOLOGY CORPORATION | WR04X9092FTL |  | G |  |  |  |  |  |  |  |
|  |  |  |  |  | 312 | 610118G00-011-G |  | RES,90.9KOhm,+/-1%,1/16W,G,SMD0402 | YAGEO CORPORATION COMPONENT | RC0402FR-0790K9L |  | G |  |  |  |  |  |  |  |
|  |  |  |  |  | 312 | 610118G00-044-G |  | RES,90.9KOhm,+/-1%,1/16W,G,SMD0402 | TA-I TECHNOLOGY CO., LTD | RM04FTN9092 |  | G |  |  |  |  |  |  |  |
|  |  |  |  |  | 312 | 610118G00-024-G |  | RES,90.9KOhm,+/-1%,1/16W,G,SMD0402 | PANASONIC INDUSTRIAL CO.,LTD. | ERJ2RKF9092X |  | G |  |  |  |  |  |  |  |
| Multi | N | ND | Y(4) | 313 | 313 | 610116J00-017-G | - | RES,1.21KOhm,+/-1%,1/16W,G,SMD0402 | KOA SPEER ELECTRONICS, INC. | RK73H1ETTP1211F | 13 | G | R332,R333,R334,R335,R336,R337,R338,R339,R340,R341,R343,R344,R345 |  |  |  |  |  |  |
|  |  |  |  |  | 313 | 610116J00-012-G |  | RES,1.21KOhm,+/-1%,1/16W,G,SMD0402 | WALSIN TECHNOLOGY CORPORATION | WR04X1211FTL |  | G |  |  |  |  |  |  |  |
|  |  |  |  |  | 313 | 610116J00-011-G |  | RES,1.21KOhm,+/-1%,1/16W,G,SMD0402 | YAGEO CORPORATION COMPONENT | RC0402FR-071K21L |  | G |  |  |  |  |  |  |  |
|  |  |  |  |  | 313 | 610116J00-044-G |  | RES,1.21KOhm,+/-1%,1/16W,G,SMD0402 | TA-I TECHNOLOGY CO., LTD | RM04FTN1211 |  | G |  |  |  |  |  |  |  |
|  |  |  |  |  | 313 | 610116J00-024-G |  | RES,1.21KOhm,+/-1%,1/16W,G,SMD0402 | PANASONIC INDUSTRIAL CO.,LTD. | ERJ2RKF1211X |  | G |  |  |  |  |  |  |  |
|  |  |  |  |  | 313 | 610116J00-029-G |  | RES,1.21KOhm,+/-1%,1/16W,G,SMD0402 | VISHAY ENTER TECHNO LOGY.INC | CRCW04021K21FKED |  | G |  |  |  |  |  |  |  |
| Multi | N | Other | Y(4) | 314 | 314 | 610114W00-017-G |  | RES,3.01KOhm,+/-1%,1/16W,G,SMD0402 | KOA SPEER ELECTRONICS, INC. | RK73H1ETTP3011F | 1 | G | R346 |  |  |  |  |  |  |
|  |  |  |  |  | 314 | 610114W00-012-G |  | RES,3.01KOhm,+/-1%,1/16W,G,SMD0402 | WALSIN TECHNOLOGY CORPORATION | WR04X3011FTL |  | G |  |  |  |  |  |  |  |
|  |  |  |  |  | 314 | 610114W00-011-G |  | RES,3.01KOhm,+/-1%,1/16W,G,SMD0402 | YAGEO CORPORATION COMPONENT | RC0402FR-073K01L |  | G |  |  |  |  |  |  |  |
|  |  |  |  |  | 314 | 610114W00-044-G |  | RES,3.01KOhm,+/-1%,1/16W,G,SMD0402 | TA-I TECHNOLOGY CO., LTD | RM04FTN3011 |  | G |  |  |  |  |  |  |  |
|  |  |  |  |  | 314 | 610114W00-029-G |  | RES,3.01KOhm,+/-1%,1/16W,G,SMD0402 | VISHAY ENTER TECHNO LOGY.INC | CRCW04023K01FKED |  | G |  |  |  |  |  |  |  |
| Multi | ND | ND | Y(4) | 315 | 315 | 61010L600-017-G |  | RES,11KOhm,+/-1%,1/16W,G,SMD0402 | KOA SPEER ELECTRONICS, INC. | RK73H1ETTP1102F | 1 | G | R349 |  |  |  |  |  |  |
|  |  |  |  |  | 315 | 61010L600-012-G |  | RES,11KOhm,+/-1%,1/16W,G,SMD0402 | WALSIN TECHNOLOGY CORPORATION | WR04X1102FTL |  | G |  |  |  |  |  |  |  |
|  |  |  |  |  | 315 | 61010L600-011-G |  | RES,11KOhm,+/-1%,1/16W,G,SMD0402 | YAGEO CORPORATION COMPONENT | RC0402FR-0711KL |  | G |  |  |  |  |  |  |  |
|  |  |  |  |  | 315 | 61010L600-044-G |  | RES,11KOhm,+/-1%,1/16W,G,SMD0402 | TA-I TECHNOLOGY CO., LTD | RM04FTN1102 |  | G |  |  |  |  |  |  |  |
|  |  |  |  |  | 315 | 61010L600-024-G |  | RES,11KOhm,+/-1%,1/16W,G,SMD0402 | PANASONIC INDUSTRIAL CO.,LTD. | ERJ2RKF1102X |  | G |  |  |  |  |  |  |  |
|  |  |  |  |  | 315 | 61010L600-029-G |  | RES,11KOhm,+/-1%,1/16W,G,SMD0402 | VISHAY ENTER TECHNO LOGY.INC | CRCW040211K0FKEDC |  | G |  |  |  |  |  |  |  |
| Multi | ND | ND | Y(4) | 316 | 316 | 61011KS00-017-G | - | RES,47KOhm,+/-1%,1/16W,G,SMD0402 | KOA SPEER ELECTRONICS, INC. | RK73H1ETTP4702F | 2 | G | R652,R658 |  |  |  |  |  |  |
|  |  |  |  |  | 316 | 61011KS00-012-G |  | RES,47KOhm,+/-1%,1/16W,G,SMD0402 | WALSIN TECHNOLOGY CORPORATION | WR04X4702FTL |  | G |  |  |  |  |  |  |  |
|  |  |  |  |  | 316 | 61011KS00-011-G |  | RES,47KOhm,+/-1%,1/16W,G,SMD0402 | YAGEO CORPORATION COMPONENT | RC0402FR-0747KL |  | G |  |  |  |  |  |  |  |
|  |  |  |  |  | 316 | 61011KS00-044-G |  | RES,47KOhm,+/-1%,1/16W,G,SMD0402 | TA-I TECHNOLOGY CO., LTD | RM04FTN4702 |  | G |  |  |  |  |  |  |  |
|  |  |  |  |  | 316 | 61011KS00-029-G |  | RES,47KOhm,+/-1%,1/16W,G,SMD0402 | VISHAY ENTER TECHNO LOGY.INC | CRCW040247K0FKED |  | G |  |  |  |  |  |  |  |
| Multi | N | other | Y(4) | 317 | 317 | 61010FL00-017-G |  | RES,2.2KOhm,+/-5%,1/16W,G,SMD0402 | KOA SPEER ELECTRONICS, INC. | RK73B1ETTP222J | 6 | G | R664,R665,R666,R673,R1020,R1021 |  |  |  |  |  |  |
|  |  |  |  |  | 317 | 61010FL01-012-G |  | RES,2.2KOhm,+/-5%,1/16W,G,SMD0402 | WALSIN TECHNOLOGY CORPORATION | WR04X222JTL |  | G |  |  |  |  |  |  |  |
|  |  |  |  |  | 317 | 61010FL00-011-G |  | RES,2.2KOhm,+/-5%,1/16W,G,SMD0402 | YAGEO CORPORATION COMPONENT | RC0402JR-072K2L |  | G |  |  |  |  |  |  |  |
|  |  |  |  |  | 317 | 61010FL00-044-G |  | RES,2.2KOhm,+/-5%,1/16W,G,SMD0402 | TA-I TECHNOLOGY CO., LTD | RM04JTN222 |  | G |  |  |  |  |  |  |  |
|  |  |  |  |  | 317 | 61010FL00-029-G |  | RES,2.2KOhm,+/-5%,1/16W,G,SMD0402 | VISHAY ENTER TECHNO LOGY.INC | CRCW04022K20JNED |  | G |  |  |  |  |  |  |  |
|  |  |  |  |  | 317 | 61010FL00-024-G |  | RES,2.2KOhm,+/-5%,1/16W,G,SMD0402 | PANASONIC INDUSTRIAL CO.,LTD. | ERJ2GEJ222X |  | G |  |  |  |  |  |  |  |
| Multi | ND | ND | Y(4) | 318 | 318 | 610112L00-017-G | - | RES,1.24KOhm,+/-1%,1/16W,G,SMD0402 | KOA SPEER ELECTRONICS, INC. | RK73H1ETTP1241F | 2 | G | R690,R753 |  |  |  |  |  |  |
|  |  |  |  |  | 318 | 610112L00-012-G |  | RES,1.24KOhm,+/-1%,1/16W,G,SMD0402 | WALSIN TECHNOLOGY CORPORATION | WR04X1241FTL |  | G |  |  |  |  |  |  |  |
|  |  |  |  |  | 318 | 610112L00-011-G |  | RES,1.24KOhm,+/-1%,1/16W,G,SMD0402 | YAGEO CORPORATION COMPONENT | RC0402FR-071K24L |  | G |  |  |  |  |  |  |  |
|  |  |  |  |  | 318 | 610112L00-044-G |  | RES,1.24KOhm,+/-1%,1/16W,G,SMD0402 | TA-I TECHNOLOGY CO., LTD | RM04FTN1241 |  | G |  |  |  |  |  |  |  |
|  |  |  |  |  | 318 | 610112L00-029-G |  | RES,1.24KOhm,+/-1%,1/16W,G,SMD0402 | VISHAY ENTER TECHNO LOGY.INC | CRCW04021K24FKED |  | G |  |  |  |  |  |  |  |
|  |  |  |  |  | 318 | 610112L00-024-G |  | RES,1.24KOhm,+/-1%,1/16W,G,SMD0402 | PANASONIC INDUSTRIAL CO.,LTD. | ERJ2RKF1241X |  | G |  |  |  |  |  |  |  |
| Multi | ND | ND | Y(4) | 319 | 319 | 610104E00-017-G | - | RES,470 Ohm,+/-1%,1/10W,G,SMD0603 | KOA SPEER ELECTRONICS, INC. | RK73H1JTTD4700F | 1 | G | R699 |  |  |  |  |  |  |
|  |  |  |  |  | 319 | 610104E00-012-G |  | RES,470 Ohm,+/-1%,1/10W,G,SMD0603 | WALSIN TECHNOLOGY CORPORATION | WR06X4700FTL |  | G |  |  |  |  |  |  |  |
|  |  |  |  |  | 319 | 610104E00-011-G |  | RES,470 Ohm,+/-1%,1/10W,G,SMD0603 | YAGEO CORPORATION COMPONENT | RC0603FR-07470RL |  | G |  |  |  |  |  |  |  |
|  |  |  |  |  | 319 | 610104E00-044-G |  | RES,470 Ohm,+/-1%,1/10W,G,SMD0603 | TA-I TECHNOLOGY CO., LTD | RM06FTN4700 |  | G |  |  |  |  |  |  |  |
|  |  |  |  |  | 319 | 610104E00-024-G |  | RES,470 Ohm,+/-1%,1/10W,G,SMD0603 | PANASONIC INDUSTRIAL CO.,LTD. | ERJ3EKF4700V |  | G |  |  |  |  |  |  |  |
| Multi | N | ND | Y(4) | 320 | 320 | 61013W100-017-G |  | RES,20mOhm,+/-1%,1/5W,G,SMD0603 | KOA SPEER ELECTRONICS, INC. | UR73D1JTTD20L0F | 1 | G | R702 |  |  |  |  |  |  |
|  |  |  |  |  | 320 | 610602500-011-G |  | RES,20mOhm,+/-1%,1/5W,G,SMD0603 | YAGEO CORPORATION COMPONENT | PF0603FRM7W0R02Z |  | G |  |  |  |  |  |  |  |
|  |  |  |  |  | 320 | 610602500-029-G |  | RES,20mOhm,+/-1%,1/5W,G,SMD0603 | VISHAY ENTER TECHNO LOGY.INC | WSL0603R0200FEA18 |  | G |  |  |  |  |  |  |  |
| Multi | ND | ND | Y(4) | 321 | 321 | 61011H500-017-G | - | RES,22 Ohm,+/-1%,1/16W,G,SMD0402 | KOA SPEER ELECTRONICS, INC. | RK73H1ETTP22R0F | 29 | G | R725,R727,R729,R730,R815,R816,R818,R1012,R1015,R1161,R1163,R1171,R1173,R1183,R1189,R1196,R1202,R1206,R1209,R1226,R1307,R1314,R1315,R1316,R1317,R1318,R1319,R1320,R1502 |  |  |  |  |  |  |
|  |  |  |  |  | 321 | 61011H500-012-G |  | RES,22 Ohm,+/-1%,1/16W,G,SMD0402 | WALSIN TECHNOLOGY CORPORATION | WR04X22R0FTL |  | G |  |  |  |  |  |  |  |
|  |  |  |  |  | 321 | 61011H500-011-G |  | RES,22 Ohm,+/-1%,1/16W,G,SMD0402 | YAGEO CORPORATION COMPONENT | RC0402FR-0722RL |  | G |  |  |  |  |  |  |  |
|  |  |  |  |  | 321 | 61011H500-044-G |  | RES,22 Ohm,+/-1%,1/16W,G,SMD0402 | TA-I TECHNOLOGY CO., LTD | RM04FTN22R0 |  | G |  |  |  |  |  |  |  |
|  |  |  |  |  | 321 | 61011H500-024-G |  | RES,22 Ohm,+/-1%,1/16W,G,SMD0402 | PANASONIC INDUSTRIAL CO.,LTD. | ERJ2RKF22R0X |  | G |  |  |  |  |  |  |  |
| Multi | ND | ND | Y(4) | 322 | 322 | 610112B00-017-G | - | RES,3.4KOhm,+/-1%,1/16W,G,SMD0402 | KOA SPEER ELECTRONICS, INC. | RK73H1ETTP3401F | 2 | G | R733,R734 |  |  |  |  |  |  |
|  |  |  |  |  | 322 | 610112B00-012-G |  | RES,3.4KOhm,+/-1%,1/16W,G,SMD0402 | WALSIN TECHNOLOGY CORPORATION | WR04X3401FTL |  | G |  |  |  |  |  |  |  |
|  |  |  |  |  | 322 | 610112B00-011-G |  | RES,3.4KOhm,+/-1%,1/16W,G,SMD0402 | YAGEO CORPORATION COMPONENT | RC0402FR-073K4L |  | G |  |  |  |  |  |  |  |
|  |  |  |  |  | 322 | 610112B00-044-G |  | RES,3.4KOhm,+/-1%,1/16W,G,SMD0402 | TA-I TECHNOLOGY CO., LTD | RM04FTN3401 |  | G |  |  |  |  |  |  |  |
| Multi | ND | ND | Y(4) | 323 | 323 | 61011B000-017-G | - | RES,1.5KOhm,+/-1%,1/16W,G,SMD0402 | KOA SPEER ELECTRONICS, INC. | RK73H1ETTP1501F | 2 | G | R738,R1111 |  |  |  |  |  |  |
|  |  |  |  |  | 323 | 61011B000-012-G |  | RES,1.5KOhm,+/-1%,1/16W,G,SMD0402 | WALSIN TECHNOLOGY CORPORATION | WR04X1501FTL |  | G |  |  |  |  |  |  |  |
|  |  |  |  |  | 323 | 61011B000-011-G |  | RES,1.5KOhm,+/-1%,1/16W,G,SMD0402 | YAGEO CORPORATION COMPONENT | RC0402FR-071K5L |  | G |  |  |  |  |  |  |  |
|  |  |  |  |  | 323 | 61011B000-044-G |  | RES,1.5KOhm,+/-1%,1/16W,G,SMD0402 | TA-I TECHNOLOGY CO., LTD | RM04FTN1501 |  | G |  |  |  |  |  |  |  |
|  |  |  |  |  | 323 | 61011B000-024-G |  | RES,1.5KOhm,+/-1%,1/16W,G,SMD0402 | PANASONIC INDUSTRIAL CO.,LTD. | ERJ2RKF1501X |  | G |  |  |  |  |  |  |  |
| Multi | N | ND | Y(4) | 324 | 324 | 610101V00-017-G | K9572 | RES,22 Ohm,+/-5%,1/16W,G,SMD0402 | KOA SPEER ELECTRONICS, INC. | RK73B1ETTP220J | 12 | G | R739,R741,R742,R743,R749,R936,R937,R993,R994,R995,R996,R997 |  |  |  |  |  |  |
|  |  |  |  |  | 324 | 610101V00-012-G |  | RES,22 Ohm,+/-5%,1/16W,G,SMD0402 | WALSIN TECHNOLOGY CORPORATION | WR04X220JTL |  | G |  |  |  |  |  |  |  |
|  |  |  |  |  | 324 | 610101V00-011-G |  | RES,22 Ohm,+/-5%,1/16W,G,SMD0402 | YAGEO CORPORATION COMPONENT | RC0402JR-0722RL |  | G |  |  |  |  |  |  |  |
|  |  |  |  |  | 324 | 610101V00-044-G |  | RES,22 Ohm,+/-5%,1/16W,G,SMD0402 | TA-I TECHNOLOGY CO., LTD | RM04JTN220 |  | G |  |  |  |  |  |  |  |
|  |  |  |  |  | 324 | 610101V00-024-G |  | RES,22 Ohm,+/-5%,1/16W,G,SMD0402 | PANASONIC INDUSTRIAL CO.,LTD. | ERJ2GEJ220X |  | G |  |  |  |  |  |  |  |
| Single | ND |  | Y(5) | 325 | 325 | 61100H601-017-G |  | RES,2KOhm,+/-0.5%,1/16W,G,SMD0402 | KOA SPEER ELECTRONICS, INC. | RN731ETTP2001D25 | 1 | G | R751 |  |  |  |  |  |  |
| Multi | ND | ND | Y(4) | 326 | 326 | 61011T800-017-G | - | RES,240 Ohm,+/-1%,1/16W,G,SMD0402 | KOA SPEER ELECTRONICS, INC. | RK73H1ETTP2400F | 1 | G | R789 |  |  |  |  |  |  |
|  |  |  |  |  | 326 | 61011T800-012-G |  | RES,240 Ohm,+/-1%,1/16W,G,SMD0402 | WALSIN TECHNOLOGY CORPORATION | WR04X2400FTL |  | G |  |  |  |  |  |  |  |
|  |  |  |  |  | 326 | 61011T800-011-G |  | RES,240 Ohm,+/-1%,1/16W,G,SMD0402 | YAGEO CORPORATION COMPONENT | RC0402FR-07240RL |  | G |  |  |  |  |  |  |  |
|  |  |  |  |  | 326 | 61011T800-044-G |  | RES,240 Ohm,+/-1%,1/16W,G,SMD0402 | TA-I TECHNOLOGY CO., LTD | RM04FTN2400 |  | G |  |  |  |  |  |  |  |
| Multi | ND | ND | Y(5) | 327 | 327 | 61100BN00-017-G |  | RES,100KOhm,+/-1%,1/16W,G,SMD0402 | KOA SPEER ELECTRONICS, INC. | RN731ETTP1003F25 | 4 | G | R790,R1154,R1157,R1237 |  |  |  |  |  |  |
|  |  |  |  |  | 327 | 61100BN00-011-G |  | RES,100KOhm,+/-1%,1/16W,G,SMD0402 | YAGEO CORPORATION COMPONENT | RT0402FRD07100KL |  | G |  |  |  |  |  |  |  |
|  |  |  |  |  | 327 | 61100BN00-044-G |  | RES,100KOhm,+/-1%,1/16W,G,SMD0402 | TA-I TECHNOLOGY CO., LTD | RB04FTP1003 |  | G |  |  |  |  |  |  |  |
|  |  |  |  |  | 327 | 61100BN00-012-G |  | RES,100KOhm,+/-1%,1/16W,G,SMD0402 | WALSIN TECHNOLOGY CORPORATION | WF04U1003FTL |  | G |  |  |  |  |  |  |  |
| Multi | N | ND | Y(4) | 328 | 328 | 610115J00-017-G | - | RES,33 Ohm,+/-1%,1/16W,G,SMD0402 | KOA SPEER ELECTRONICS, INC. | RK73H1ETTP33R0F | 11 | G | R792,R793,R794,R796,R797,R799,R925,R927,R929,R1019,R1025 |  |  |  |  |  |  |
|  |  |  |  |  | 328 | 610115J00-012-G |  | RES,33 Ohm,+/-1%,1/16W,G,SMD0402 | WALSIN TECHNOLOGY CORPORATION | WR04X33R0FTL |  | G |  |  |  |  |  |  |  |
|  |  |  |  |  | 328 | 610115J00-011-G |  | RES,33 Ohm,+/-1%,1/16W,G,SMD0402 | YAGEO CORPORATION COMPONENT | RC0402FR-0733RL |  | G |  |  |  |  |  |  |  |
|  |  |  |  |  | 328 | 610115J00-044-G |  | RES,33 Ohm,+/-1%,1/16W,G,SMD0402 | TA-I TECHNOLOGY CO., LTD | RM04FTN33R0 |  | G |  |  |  |  |  |  |  |
|  |  |  |  |  | 328 | 610115J00-024-G |  | RES,33 Ohm,+/-1%,1/16W,G,SMD0402 | PANASONIC INDUSTRIAL CO.,LTD. | ERJ2RKF33R0X |  | G |  |  |  |  |  |  |  |
| Multi | ND | ND | Y(4) | 329 | 329 | 61011H100-017-G | - | RES,220 Ohm,+/-1%,1/16W,G,SMD0402 | KOA SPEER ELECTRONICS, INC. | RK73H1ETTP2200F | 7 | G | R831,R832,R833,R834,R1345,R1347,R1494 |  |  |  |  |  |  |
|  |  |  |  |  | 329 | 61011H100-012-G |  | RES,220 Ohm,+/-1%,1/16W,G,SMD0402 | WALSIN TECHNOLOGY CORPORATION | WR04X2200FTL |  | G |  |  |  |  |  |  |  |
|  |  |  |  |  | 329 | 61011H100-011-G |  | RES,220 Ohm,+/-1%,1/16W,G,SMD0402 | YAGEO CORPORATION COMPONENT | RC0402FR-07220RL |  | G |  |  |  |  |  |  |  |
|  |  |  |  |  | 329 | 61011H100-044-G |  | RES,220 Ohm,+/-1%,1/16W,G,SMD0402 | TA-I TECHNOLOGY CO., LTD | RM04FTN2200 |  | G |  |  |  |  |  |  |  |
|  |  |  |  |  | 329 | 61011H100-024-G |  | RES,220 Ohm,+/-1%,1/16W,G,SMD0402 | PANASONIC INDUSTRIAL CO.,LTD. | ERJ2RKF2200X |  | G |  |  |  |  |  |  |  |
|  |  |  |  |  | 329 | 61011H100-029-G |  | RES,220 Ohm,+/-1%,1/16W,G,SMD0402 | VISHAY ENTER TECHNO LOGY.INC | CRCW0402220RFKEDC |  | G |  |  |  |  |  |  |  |
| Multi | ND |  | Y(4) | 330 | 330 | 61011U901-017-G |  | RES,120Ohm,+/-1%,1/20W,G,SMD0201 | KOA SPEER ELECTRONICS, INC. | RK73H1HTTC1200F | 48 | G | R839,R840,R841,R842,R843,R844,R845,R846,R847,R848,R849,R850,R851,R852,R853,R854,R855,R856,R857,R858,R859,R860,R861,R862,R867,R868,R869,R870,R871,R872,R873,R874,R875,R876,R877,R878,R879,R880,R881,R882,R883,R884,R885,R887,R888,R889,R890,R891 |  |  |  |  |  |  |
|  |  |  |  |  | 330 | 61011U900-011-G |  | RES,thick film,120Ohm,+/-1%,1/20W,SMD0201,G | YAGEO CORPORATION COMPONENT | RC0201FR-07120RL |  | G |  |  |  |  |  |  |  |
|  |  |  |  |  | 330 | 61011U900-012-G |  | RES,thick film,120Ohm,+/-1%,1/20W,SMD0201,G | WALSIN TECHNOLOGY CORPORATION | WR02X1200FAL |  | G |  |  |  |  |  |  |  |
|  |  |  |  |  | 330 | 61011U900-044-G |  | RES,thick film,120Ohm,+/-1%,1/20W,SMD0201,G | TA-I TECHNOLOGY CO., LTD | RM02FTN1200 |  | G |  |  |  |  |  |  |  |
| Multi | ND | ND | Y(4) | 331 | 331 | 61011KH00-017-G | - | RES,240 Ohm,+/-5%,1/16W,G,SMD0402 | KOA SPEER ELECTRONICS, INC. | RK73B1ETTP241J | 1 | G | R886 |  |  |  |  |  |  |
|  |  |  |  |  | 331 | 61011KH00-012-G |  | RES,240 Ohm,+/-5%,1/16W,G,SMD0402 | WALSIN TECHNOLOGY CORPORATION | WR04X241JTL |  | G |  |  |  |  |  |  |  |
|  |  |  |  |  | 331 | 61011KH00-011-G |  | RES,240 Ohm,+/-5%,1/16W,G,SMD0402 | YAGEO CORPORATION COMPONENT | RC0402JR-07240RL |  | G |  |  |  |  |  |  |  |
|  |  |  |  |  | 331 | 61011KH00-044-G |  | RES,240 Ohm,+/-5%,1/16W,G,SMD0402 | TA-I TECHNOLOGY CO., LTD | RM04JTN241 |  | G |  |  |  |  |  |  |  |
|  |  |  |  |  | 331 | 61011KH00-024-G |  | RES,240 Ohm,+/-5%,1/16W,G,SMD0402 | PANASONIC INDUSTRIAL CO.,LTD. | ERJ2GEJ241X |  | G |  |  |  |  |  |  |  |
| Multi | N |  | Y(5) | 332 | 332 | 61100LV00-017-G |  | RES,10KOhm,+/-1%,1/16W,G,SMD0402 | KOA SPEER ELECTRONICS, INC. | RN731ETTP1002F50 | 9 | G | R940,R966,R998,R999,R1084,R1085,R1088,R1261,R1751 |  |  |  |  |  |  |
|  |  |  |  |  | 332 | 61100LV00-011-G |  | RES,10KOhm,+/-1%,1/16W,G,SMD0402 | YAGEO CORPORATION COMPONENT | RT0402FRE0710KL |  | G |  |  |  |  |  |  |  |
|  |  |  |  |  | 332 | 61100LV00-044-G |  | RES,10KOhm,+/-1%,1/16W,G,SMD0402 | TA-I TECHNOLOGY CO., LTD | RB04FTS1002 |  | G |  |  |  |  |  |  |  |
|  |  |  |  |  | 332 | 61100LV00-012-G |  | RES,10KOhm,+/-1%,1/16W,G,SMD0402 | WALSIN TECHNOLOGY CORPORATION | WF04T1002FTL |  | G |  |  |  |  |  |  |  |
| Multi | ND | ND | Y(4) | 333 | 333 | 610114U00-017-G |  | RES,3.3KOhm,+/-1%,1/16W,G,SMD0402 | KOA SPEER ELECTRONICS, INC. | RK73H1ETTP3301F | 21 | G | R960,R1323,R1325,R1327,R1328,R1412,R1413,R1414,R1416,R1417,R1418,R1422,R1423,R1424,R1426,R1427,R1428,R1505,R1506,R1523,R1783 |  |  |  |  |  |  |
|  |  |  |  |  | 333 | 610114U00-012-G |  | RES,3.3KOhm,+/-1%,1/16W,G,SMD0402 | WALSIN TECHNOLOGY CORPORATION | WR04X3301FTL |  | G |  |  |  |  |  |  |  |
|  |  |  |  |  | 333 | 610114U00-011-G |  | RES,3.3KOhm,+/-1%,1/16W,G,SMD0402 | YAGEO CORPORATION COMPONENT | RC0402FR-073K3L |  | G |  |  |  |  |  |  |  |
|  |  |  |  |  | 333 | 610114U00-044-G |  | RES,3.3KOhm,+/-1%,1/16W,G,SMD0402 | TA-I TECHNOLOGY CO., LTD | RM04FTN3301 |  | G |  |  |  |  |  |  |  |
|  |  |  |  |  | 333 | 610114U00-024-G |  | RES,3.3KOhm,+/-1%,1/16W,G,SMD0402 | PANASONIC INDUSTRIAL CO.,LTD. | ERJ2RKF3301X |  | G |  |  |  |  |  |  |  |
| Multi | ND | ND | Y(5) | 334 | 334 | 61100C600-017-G |  | RES,1KOhm,+/-0.5%,1/16W,G,SMD0402 | KOA SPEER ELECTRONICS, INC. | RN731ETTP1001D25 | 19 | G | R961,R962,R963,R964,R965,R967,R968,R969,R970,R975,R976,R977,R978,R985,R986,R988,R989,R992,R1003 |  |  |  |  |  |  |
|  |  |  |  |  | 334 | 61100C603-024-G |  | RES,1KOhm,+/-0.5%,1/16W,G,SMD0402 | PANASONIC INDUSTRIAL CO.,LTD. | ERA2AED102X |  | G |  |  |  |  |  |  |  |
|  |  |  |  |  | 334 | 61100C600-029-G |  | RES,1KOhm,+/-0.5%,1/16W,G,SMD0402 | VISHAY ENTER TECHNO LOGY.INC | MCS04020D1001DE000 |  | G |  |  |  |  |  |  |  |
|  |  |  |  |  | 334 | 61100C600-011-G |  | RES,1KOhm,+/-0.5%,1/16W,G,SMD0402 | YAGEO CORPORATION COMPONENT | RT0402DRE071KL |  | G |  |  |  |  |  |  |  |
| Multi | N | ND | Y(4) | 335 | 335 | 61010A000-017-G | - | RES,8.2KOhm,+/-5%,1/16W,G,SMD0402 | KOA SPEER ELECTRONICS, INC. | RK73B1ETTP822J | 1 | G | R971 |  |  |  |  |  |  |
|  |  |  |  |  | 335 | 61010A000-012-G |  | RES,8.2KOhm,+/-5%,1/16W,G,SMD0402 | WALSIN TECHNOLOGY CORPORATION | WR04X822JTL |  | G |  |  |  |  |  |  |  |
|  |  |  |  |  | 335 | 61010A000-011-G |  | RES,8.2KOhm,+/-5%,1/16W,G,SMD0402 | YAGEO CORPORATION COMPONENT | RC0402JR-078K2L |  | G |  |  |  |  |  |  |  |
|  |  |  |  |  | 335 | 61010A000-044-G |  | RES,8.2KOhm,+/-5%,1/16W,G,SMD0402 | TA-I TECHNOLOGY CO., LTD | RM04JTN822 |  | G |  |  |  |  |  |  |  |
|  |  |  |  |  | 335 | 61010A000-024-G |  | RES,8.2KOhm,+/-5%,1/16W,G,SMD0402 | PANASONIC INDUSTRIAL CO.,LTD. | ERJ2GEJ822X |  | G |  |  |  |  |  |  |  |
| Multi | ND | ND | Y(4) | 336 | 336 | 610115V00-017-G | - | RES,300 Ohm,+/-1%,1/16W,G,SMD0402 | KOA SPEER ELECTRONICS, INC. | RK73H1ETTP3000F | 48 | G | R991,R1440,R1446,R1447,R1448,R1449,R1450,R1451,R1594,R1595,R1596,R1597,R1598,R1601,R1602,R1607,R1608,R1609,R1610,R1611,R1612,R1613,R1614,R1615,R1616,R1617,R1618,R1619,R1620,R1621,R1622,R1623,R1624,R1625,R1626,R1627,R1628,R1629,R1630,R1631,R1632,R1633,R1634,R1635,R1636,R1637,R1638,R1723 |  |  |  |  |  |  |
|  |  |  |  |  | 336 | 610115V00-012-G |  | RES,300 Ohm,+/-1%,1/16W,G,SMD0402 | WALSIN TECHNOLOGY CORPORATION | WR04X3000FTL |  | G |  |  |  |  |  |  |  |
|  |  |  |  |  | 336 | 610115V00-011-G |  | RES,300 Ohm,+/-1%,1/16W,G,SMD0402 | YAGEO CORPORATION COMPONENT | RC0402FR-07300RL |  | G |  |  |  |  |  |  |  |
|  |  |  |  |  | 336 | 610115V00-044-G |  | RES,300 Ohm,+/-1%,1/16W,G,SMD0402 | TA-I TECHNOLOGY CO., LTD | RM04FTN3000 |  | G |  |  |  |  |  |  |  |
| Multi | N | ND | Y(4) | 337 | 337 | 610118100-017-G | - | RES,1.4KOhm,+/-1%,1/16W,G,SMD0402 | KOA SPEER ELECTRONICS, INC. | RK73H1ETTP1401F | 2 | G | R1000,R1002 |  |  |  |  |  |  |
|  |  |  |  |  | 337 | 610118100-012-G |  | RES,1.4KOhm,+/-1%,1/16W,G,SMD0402 | WALSIN TECHNOLOGY CORPORATION | WR04X1401FTL |  | G |  |  |  |  |  |  |  |
|  |  |  |  |  | 337 | 610118100-011-G |  | RES,1.4KOhm,+/-1%,1/16W,G,SMD0402 | YAGEO CORPORATION COMPONENT | RC0402FR-071K4L |  | G |  |  |  |  |  |  |  |
|  |  |  |  |  | 337 | 610118100-044-G |  | RES,1.4KOhm,+/-1%,1/16W,G,SMD0402 | TA-I TECHNOLOGY CO., LTD | RM04FTN1401 |  | G |  |  |  |  |  |  |  |
|  |  |  |  |  | 337 | 610118100-024-G |  | RES,1.4KOhm,+/-1%,1/16W,G,SMD0402 | PANASONIC INDUSTRIAL CO.,LTD. | ERJ2RKF1401X |  | G |  |  |  |  |  |  |  |
| Multi | N | ND | Y(4) | 338 | 338 | 61010FF00-017-G | - | RES,150 Ohm,+/-1%,1/16W,G,SMD0402 | KOA SPEER ELECTRONICS, INC. | RK73H1ETTP1500F | 6 | G | R1006,R1007,R1008,R1009,R1010,R1011 |  |  |  |  |  |  |
|  |  |  |  |  | 338 | 61010FF00-012-G |  | RES,150 Ohm,+/-1%,1/16W,G,SMD0402 | WALSIN TECHNOLOGY CORPORATION | WR04X1500FTL |  | G |  |  |  |  |  |  |  |
|  |  |  |  |  | 338 | 61010FF00-011-G |  | RES,150 Ohm,+/-1%,1/16W,G,SMD0402 | YAGEO CORPORATION COMPONENT | RC0402FR-07150RL |  | G |  |  |  |  |  |  |  |
|  |  |  |  |  | 338 | 61010FF00-044-G |  | RES,150 Ohm,+/-1%,1/16W,G,SMD0402 | TA-I TECHNOLOGY CO., LTD | RM04FTN1500 |  | G |  |  |  |  |  |  |  |
|  |  |  |  |  | 338 | 61010FF00-024-G |  | RES,150 Ohm,+/-1%,1/16W,G,SMD0402 | PANASONIC INDUSTRIAL CO.,LTD. | ERJ2RKF1500X |  | G |  |  |  |  |  |  |  |
| Multi | N | Other | Y(4) | 339 | 339 | 610114R00-017-G |  | RES,49.9KOhm,+/-1%,1/16W,G,SMD0402 | KOA SPEER ELECTRONICS, INC. | RK73H1ETTP4992F | 1 | G | R1026 |  |  |  |  |  |  |
|  |  |  |  |  | 339 | 610114R00-012-G |  | RES,49.9KOhm,+/-1%,1/16W,G,SMD0402 | WALSIN TECHNOLOGY CORPORATION | WR04X4992FTL |  | G |  |  |  |  |  |  |  |
|  |  |  |  |  | 339 | 610114R00-011-G |  | RES,49.9KOhm,+/-1%,1/16W,G,SMD0402 | YAGEO CORPORATION COMPONENT | RC0402FR-0749K9L |  | G |  |  |  |  |  |  |  |
|  |  |  |  |  | 339 | 610114R00-044-G |  | RES,49.9KOhm,+/-1%,1/16W,G,SMD0402 | TA-I TECHNOLOGY CO., LTD | RM04FTN4992 |  | G |  |  |  |  |  |  |  |
|  |  |  |  |  | 339 | 610114R00-029-G |  | RES,49.9KOhm,+/-1%,1/16W,G,SMD0402 | VISHAY ENTER TECHNO LOGY.INC | CRCW040249K9FKED |  | G |  |  |  |  |  |  |  |
| Multi | N | ND | Y(4) | 340 | 340 | 610115W00-017-G | - | RES,18KOhm,+/-1%,1/16W,G,SMD0402 | KOA SPEER ELECTRONICS, INC. | RK73H1ETTP1802F | 1 | G | R1027 |  |  |  |  |  |  |
|  |  |  |  |  | 340 | 610115W00-012-G |  | RES,18KOhm,+/-1%,1/16W,G,SMD0402 | WALSIN TECHNOLOGY CORPORATION | WR04X1802FTL |  | G |  |  |  |  |  |  |  |
|  |  |  |  |  | 340 | 610115W00-011-G |  | RES,18KOhm,+/-1%,1/16W,G,SMD0402 | YAGEO CORPORATION COMPONENT | RC0402FR-0718KL |  | G |  |  |  |  |  |  |  |
|  |  |  |  |  | 340 | 610115W00-044-G |  | RES,18KOhm,+/-1%,1/16W,G,SMD0402 | TA-I TECHNOLOGY CO., LTD | RM04FTN1802 |  | G |  |  |  |  |  |  |  |
|  |  |  |  |  | 340 | 610115W00-024-G |  | RES,18KOhm,+/-1%,1/16W,G,SMD0402 | PANASONIC INDUSTRIAL CO.,LTD. | ERJ2RKF1802X |  | G |  |  |  |  |  |  |  |
| Multi | ND |  | Y(4) | 341 | 341 | 61011GN00-017-G |  | RES,1.6KOhm,+/-1%,1/16W,G,SMD0402 | KOA SPEER ELECTRONICS, INC. | RK73H1ETTP1601F | 3 | G | R1089,R1460,R1462 |  |  |  |  |  |  |
|  |  |  |  |  | 341 | 61011GN00-012-G |  | RES,1.6KOhm,+/-1%,1/16W,G,SMD0402 | WALSIN TECHNOLOGY CORPORATION | WR04X1601FTL |  | G |  |  |  |  |  |  |  |
|  |  |  |  |  | 341 | 61011GN00-011-G |  | RES,1.6KOhm,+/-1%,1/16W,G,SMD0402 | YAGEO CORPORATION COMPONENT | RC0402FR-071K6L |  | G |  |  |  |  |  |  |  |
|  |  |  |  |  | 341 | 61011GN00-044-G |  | RES,1.6KOhm,+/-1%,1/16W,G,SMD0402 | TA-I TECHNOLOGY CO., LTD | RM04FTN1601 |  | G |  |  |  |  |  |  |  |
| Multi | ND | ND | Y(4) | 342 | 342 | 610118400-017-G |  | RES,27 Ohm,+/-1%,1/16W,G,SMD0402 | KOA SPEER ELECTRONICS, INC. | RK73H1ETTP27R0F | 12 | G | R1091,R1094,R1095,R1096,R1097,R1098,R1102,R1104,R1105,R1106,R1108,R1109 |  |  |  |  |  |  |
|  |  |  |  |  | 342 | 610118400-012-G |  | RES,27 Ohm,+/-1%,1/16W,G,SMD0402 | WALSIN TECHNOLOGY CORPORATION | WR04X27R0FTL |  | G |  |  |  |  |  |  |  |
|  |  |  |  |  | 342 | 610118400-011-G |  | RES,27 Ohm,+/-1%,1/16W,G,SMD0402 | YAGEO CORPORATION COMPONENT | RC0402FR-0727RL |  | G |  |  |  |  |  |  |  |
|  |  |  |  |  | 342 | 610118400-044-G |  | RES,27 Ohm,+/-1%,1/16W,G,SMD0402 | TA-I TECHNOLOGY CO., LTD | RM04FTN27R0 |  | G |  |  |  |  |  |  |  |
| Multi | N |  | Y(5) | 343 | 343 | 61100QH00-017-G |  | RES,510 Ohm,+/-0.1%,1/16W,G,SMD0402 | KOA SPEER ELECTRONICS, INC. | RN731ETTP5100B25 | 2 | G | R1092,R1115 |  |  |  |  |  |  |
|  |  |  |  |  | 343 | 61100QH00-011-G |  | RES,510 Ohm,+/-0.1%,1/16W,G,SMD0402 | YAGEO CORPORATION COMPONENT | RT0402BRD07510RL |  | G |  |  |  |  |  |  |  |
|  |  |  |  |  | 343 | 61100QH00-044-G |  | RES,510 Ohm,+/-0.1%,1/16W,G,SMD0402 | TA-I TECHNOLOGY CO., LTD | RB04BTP5100 |  | G |  |  |  |  |  |  |  |
|  |  |  |  |  | 343 | 61100QH00-012-G |  | RES,510 Ohm,+/-0.1%,1/16W,G,SMD0402 | WALSIN TECHNOLOGY CORPORATION | WF04U5100BTL |  | G |  |  |  |  |  |  |  |
| Multi | ND | ND | Y(4) | 344 | 344 | 610112800-017-G | - | RES,6.04KOhm,+/-1%,1/16W,G,SMD0402 | KOA SPEER ELECTRONICS, INC. | RK73H1ETTP6041F | 1 | G | R1147 |  |  |  |  |  |  |
|  |  |  |  |  | 344 | 610112800-012-G |  | RES,6.04KOhm,+/-1%,1/16W,G,SMD0402 | WALSIN TECHNOLOGY CORPORATION | WR04X6041FTL |  | G |  |  |  |  |  |  |  |
|  |  |  |  |  | 344 | 610112800-011-G |  | RES,6.04KOhm,+/-1%,1/16W,G,SMD0402 | YAGEO CORPORATION COMPONENT | RC0402FR-076K04L |  | G |  |  |  |  |  |  |  |
|  |  |  |  |  | 344 | 610112800-044-G |  | RES,6.04KOhm,+/-1%,1/16W,G,SMD0402 | TA-I TECHNOLOGY CO., LTD | RM04FTN6041 |  | G |  |  |  |  |  |  |  |
|  |  |  |  |  | 344 | 610112800-029-G |  | RES,6.04KOhm,+/-1%,1/16W,G,SMD0402 | VISHAY ENTER TECHNO LOGY.INC | CRCW04026K04FKED |  | G |  |  |  |  |  |  |  |
| Multi | N | ND | Y(5) | 345 | 345 | 61100FR00-017-G |  | RES,13KOhm,+/-1%,1/16W,G,SMD0402 | KOA SPEER ELECTRONICS, INC. | RN731ETTP1302F25 | 1 | G | R1255 |  |  |  |  |  |  |
|  |  |  |  |  | 345 | 61100FR00-044-G |  | RES,13KOhm,+/-1%,1/16W,G,SMD0402 | TA-I TECHNOLOGY CO., LTD | RB04FTP1302 |  | G |  |  |  |  |  |  |  |
| Multi | ND | ND | Y(5) | 346 | 346 | 61100BK00-017-G |  | RES,47KOhm,+/-1%,1/16W,G,SMD0402 | KOA SPEER ELECTRONICS, INC. | RN731ETTP4702F25 | 1 | G | R1262 |  |  |  |  |  |  |
|  |  |  |  |  | 346 | 61100BK00-011-G |  | RES,47KOhm,+/-1%,1/16W,G,SMD0402 | YAGEO CORPORATION COMPONENT | RT0402FRD0747KL |  | G |  |  |  |  |  |  |  |
|  |  |  |  |  | 346 | 61100BK00-044-G |  | RES,47KOhm,+/-1%,1/16W,G,SMD0402 | TA-I TECHNOLOGY CO., LTD | RB04FTP4702 |  | G |  |  |  |  |  |  |  |
|  |  |  |  |  | 346 | 61100BK00-012-G |  | RES,47KOhm,+/-1%,1/16W,G,SMD0402 | WALSIN TECHNOLOGY CORPORATION | WF04U4702FTL |  | G |  |  |  |  |  |  |  |
| Multi | N | ND | Y(4) | 347 | 347 | 610112N00-017-G | - | RES,130 Ohm,+/-1%,1/16W,G,SMD0402 | KOA SPEER ELECTRONICS, INC. | RK73H1ETTP1300F | 1 | G | R1280 |  |  |  |  |  |  |
|  |  |  |  |  | 347 | 610112N00-012-G |  | RES,130 Ohm,+/-1%,1/16W,G,SMD0402 | WALSIN TECHNOLOGY CORPORATION | WR04X1300FTL |  | G |  |  |  |  |  |  |  |
|  |  |  |  |  | 347 | 610112N00-011-G |  | RES,130 Ohm,+/-1%,1/16W,G,SMD0402 | YAGEO CORPORATION COMPONENT | RC0402FR-07130RL |  | G |  |  |  |  |  |  |  |
|  |  |  |  |  | 347 | 610112N00-044-G |  | RES,130 Ohm,+/-1%,1/16W,G,SMD0402 | TA-I TECHNOLOGY CO., LTD | RM04FTN1300 |  | G |  |  |  |  |  |  |  |
|  |  |  |  |  | 347 | 610112N00-029-G |  | RES,130 Ohm,+/-1%,1/16W,G,SMD0402 | VISHAY ENTER TECHNO LOGY.INC | CRCW0402130RFKED |  | G |  |  |  |  |  |  |  |
|  |  |  |  |  | 347 | 610112N00-024-G |  | RES,130 Ohm,+/-1%,1/16W,G,SMD0402 | PANASONIC INDUSTRIAL CO.,LTD. | ERJ2RKF1300X |  | G |  |  |  |  |  |  |  |
| Multi | ND |  | Y(4) | 348 | 348 | 61011CB00-017-G |  | RES,64.9 Ohm,+/-1%,1/16W,G,SMD0402 | KOA SPEER ELECTRONICS, INC. | RK73H1ETTP64R9F | 1 | G | R1288 |  |  |  |  |  |  |
|  |  |  |  |  | 348 | 61011CB00-012-G |  | RES,64.9 Ohm,+/-1%,1/16W,G,SMD0402 | WALSIN TECHNOLOGY CORPORATION | WR04X64R9FTL |  | G |  |  |  |  |  |  |  |
|  |  |  |  |  | 348 | 61011CB00-011-G |  | RES,64.9 Ohm,+/-1%,1/16W,G,SMD0402 | YAGEO CORPORATION COMPONENT | RC0402FR-0764R9L |  | G |  |  |  |  |  |  |  |
|  |  |  |  |  | 348 | 61011CB00-044-G |  | RES,64.9 Ohm,+/-1%,1/16W,G,SMD0402 | TA-I TECHNOLOGY CO., LTD | RM04FTN64R9 |  | G |  |  |  |  |  |  |  |
| Multi | N | other | Y(4) | 349 | 349 | 61010AC00-017-G |  | RES,2.2 Ohm,+/-1%,1/10W,G,SMD0603 | KOA SPEER ELECTRONICS, INC. | RK73H1JTTD2R20F | 1 | G | R1298 |  |  |  |  |  |  |
|  |  |  |  |  | 349 | 61010AC00-012-G |  | RES,2.2 Ohm,+/-1%,1/10W,G,SMD0603 | WALSIN TECHNOLOGY CORPORATION | WR06W2R20FTL |  | G |  |  |  |  |  |  |  |
|  |  |  |  |  | 349 | 61010AC00-011-G |  | RES,2.2 Ohm,+/-1%,1/10W,G,SMD0603 | YAGEO CORPORATION COMPONENT | RC0603FR-072R2L |  | G |  |  |  |  |  |  |  |
|  |  |  |  |  | 349 | 61010AC00-044-G |  | RES,2.2 Ohm,+/-1%,1/10W,G,SMD0603 | TA-I TECHNOLOGY CO., LTD | RM06FTN2R20 |  | G |  |  |  |  |  |  |  |
|  |  |  |  |  | 349 | 61010AC00-024-G |  | RES,2.2 Ohm,+/-1%,1/10W,G,SMD0603 | PANASONIC INDUSTRIAL CO.,LTD. | ERJ3RQF2R2V |  | G |  |  |  |  |  |  |  |
| Multi | ND | ND | Y(5) | 350 | 350 | 61100AH00-017-G |  | RES,10KOhm,+/-0.5%,1/16W,G,SMD0402 | KOA SPEER ELECTRONICS, INC. | RN731ETTP1002D25 | 8 | G | R1303,R1304,R1305,R1308,R1310,R1311,R1312,R1313 |  |  |  |  |  |  |
|  |  |  |  |  | 350 | 61100AH00-011-G |  | RES,10KOhm,+/-0.5%,1/16W,G,SMD0402 | YAGEO CORPORATION COMPONENT | RT0402DRE0710KL |  | G |  |  |  |  |  |  |  |
|  |  |  |  |  | 350 | 61100AH00-044-G |  | RES,10KOhm,+/-0.5%,1/16W,G,SMD0402 | TA-I TECHNOLOGY CO., LTD | RB04DTP1002 |  | G |  |  |  |  |  |  |  |
|  |  |  |  |  | 350 | 61100AH00-012-G |  | RES,10KOhm,+/-0.5%,1/16W,G,SMD0402 | WALSIN TECHNOLOGY CORPORATION | WF04U1002DTL |  | G |  |  |  |  |  |  |  |
| Multi | ND | ND | Y(4) | 351 | 351 | 610115N00-017-G |  | RES,2.4KOhm,+/-1%,1/16W,G,SMD0402 | KOA SPEER ELECTRONICS, INC. | RK73H1ETTP2401F | 2 | G | R1331,R1332 |  |  |  |  |  |  |
|  |  |  |  |  | 351 | 610115N00-012-G |  | RES,2.4KOhm,+/-1%,1/16W,G,SMD0402 | WALSIN TECHNOLOGY CORPORATION | WR04X2401FTL |  | G |  |  |  |  |  |  |  |
|  |  |  |  |  | 351 | 610115N00-011-G |  | RES,2.4KOhm,+/-1%,1/16W,G,SMD0402 | YAGEO CORPORATION COMPONENT | RC0402FR-072K4L |  | G |  |  |  |  |  |  |  |
|  |  |  |  |  | 351 | 610115N00-044-G |  | RES,2.4KOhm,+/-1%,1/16W,G,SMD0402 | TA-I TECHNOLOGY CO., LTD | RM04FTN2401 |  | G |  |  |  |  |  |  |  |
| Multi | N | Other | Y(4) | 352 | 352 | 61011BW00-017-G |  | RES,1.2KOhm,+/-1%,1/16W,G,SMD0402 | KOA SPEER ELECTRONICS, INC. | RK73H1ETTP1201F | 2 | G | R1393,R1394 |  |  |  |  |  |  |
|  |  |  |  |  | 352 | 61011BW00-012-G |  | RES,1.2KOhm,+/-1%,1/16W,G,SMD0402 | WALSIN TECHNOLOGY CORPORATION | WR04X1201FTL |  | G |  |  |  |  |  |  |  |
|  |  |  |  |  | 352 | 61011BW00-011-G |  | RES,1.2KOhm,+/-1%,1/16W,G,SMD0402 | YAGEO CORPORATION COMPONENT | RC0402FR-071K2L |  | G |  |  |  |  |  |  |  |
|  |  |  |  |  | 352 | 61011BW00-044-G |  | RES,1.2KOhm,+/-1%,1/16W,G,SMD0402 | TA-I TECHNOLOGY CO., LTD | RM04FTN1201 |  | G |  |  |  |  |  |  |  |
| Multi | N | ND | Y(4) | 353 | 353 | 610103300-017-G | - | RES,100KOhm,+/-5%,1/16W,G,SMD0402 | KOA SPEER ELECTRONICS, INC. | RK73B1ETTP104J | 2 | G | R1395,R1398 |  |  |  |  |  |  |
|  |  |  |  |  | 353 | 610103300-012-G |  | RES,100KOhm,+/-5%,1/16W,G,SMD0402 | WALSIN TECHNOLOGY CORPORATION | WR04X104JTL |  | G |  |  |  |  |  |  |  |
|  |  |  |  |  | 353 | 610103300-011-G |  | RES,100KOhm,+/-5%,1/16W,G,SMD0402 | YAGEO CORPORATION COMPONENT | RC0402JR-07100KL |  | G |  |  |  |  |  |  |  |
|  |  |  |  |  | 353 | 610103300-044-G |  | RES,100KOhm,+/-5%,1/16W,G,SMD0402 | TA-I TECHNOLOGY CO., LTD | RM04JTN104 |  | G |  |  |  |  |  |  |  |
|  |  |  |  |  | 353 | 610103300-029-G |  | RES,100KOhm,+/-5%,1/16W,G,SMD0402 | VISHAY ENTER TECHNO LOGY.INC | CRCW0402100KJNED |  | G |  |  |  |  |  |  |  |
| Multi | ND | ND | Y(4) | 354 | 354 | 61012LR00-017-G |  | RES,1KOhm,+/-0.5%,1/16W,G,SMD0402 | KOA SPEER ELECTRONICS, INC. | RK73H1ETTP1001D | 1 | G | R1480 |  |  |  |  |  |  |
|  |  |  |  |  | 354 | 61012LR00-012-G |  | RES,1KOhm,+/-0.5%,1/16W,G,SMD0402 | WALSIN TECHNOLOGY CORPORATION | WF04H1001DTL |  | G |  |  |  |  |  |  |  |
|  |  |  |  |  | 354 | 61012LR00-011-G |  | RES,1KOhm,+/-0.5%,1/16W,G,SMD0402 | YAGEO CORPORATION COMPONENT | RC0402DR-071KL |  | G |  |  |  |  |  |  |  |
|  |  |  |  |  | 354 | 61012LR00-044-G |  | RES,1KOhm,+/-0.5%,1/16W,G,SMD0402 | TA-I TECHNOLOGY CO., LTD | RM04DTN1001 |  | G |  |  |  |  |  |  |  |
| Multi | ND | ND | N | 355 | 355 | 61100QT01-017-G | - | RES,10 Ohm,+/-0.5%,1/16W,G,SMD0402 | KOA SPEER ELECTRONICS, INC. | RN731ETTP10R0D25 | 1 | G | R1483 |  |  |  |  |  |  |
|  |  |  |  |  | 355 | 61100QT00-011-G |  | RES,10 Ohm,+/-0.5%,1/16W,G,SMD0402 | YAGEO CORPORATION COMPONENT | RT0402DRE0710RL |  | G |  |  |  |  |  |  |  |
|  |  |  |  |  | 355 | 61100QT00-012-G |  | RES,10 Ohm,+/-0.5%,1/16W,G,SMD0402 | WALSIN TECHNOLOGY CORPORATION | WF04T10R0DTL |  | G |  |  |  |  |  |  |  |
| Multi | N |  | Y(5) | 356 | 356 | 61100LQ00-017-G |  | RES,20KOhm,+/-1%,1/16W,G,SMD0402 | KOA SPEER ELECTRONICS, INC. | RN731ETTP2002F50 | 1 | G | R1488 |  |  |  |  |  |  |
|  |  |  |  |  | 356 | 61100LQ00-011-G |  | RES,20KOhm,+/-1%,1/16W,G,SMD0402 | YAGEO CORPORATION COMPONENT | RT0402FRE0720KL |  | G |  |  |  |  |  |  |  |
|  |  |  |  |  | 356 | 61100LQ00-044-G |  | RES,20KOhm,+/-1%,1/16W,G,SMD0402 | TA-I TECHNOLOGY CO., LTD | RB04FTS2002 |  | G |  |  |  |  |  |  |  |
|  |  |  |  |  | 356 | 61100LQ00-012-G |  | RES,20KOhm,+/-1%,1/16W,G,SMD0402 | WALSIN TECHNOLOGY CORPORATION | WF04T2002FTL |  | G |  |  |  |  |  |  |  |
| Multi |  |  | Y(4) | 357 | 357 | 610118800-017-G |  | RES,499KOhm,+/-1%,1/8W,G,SMD0805 | KOA SPEER ELECTRONICS, INC. | RK73H2ATTD4993F | 1 | G | R1492 |  |  |  |  |  |  |
|  |  |  |  |  | 357 | 610118800-024-G |  | RES,499KOhm,+/-1%,1/8W,G,SMD0805 | PANASONIC INDUSTRIAL CO.,LTD. | ERJ6ENF4993V |  | G |  |  |  |  |  |  |  |
|  |  |  |  |  | 357 | 610118800-011-G |  | RES,499KOhm,+/-1%,1/8W,G,SMD0805 | YAGEO CORPORATION COMPONENT | RC0805FR-07499KL |  | G |  |  |  |  |  |  |  |
| Multi | ND | ND | Y(4) | 358 | 358 | 61011LF00-017-G | - | RES,499KOhm,+/-1%,1/16W,G,SMD0402 | KOA SPEER ELECTRONICS, INC. | RK73H1ETTP4993F | 2 | G | R1493,R1847 |  |  |  |  |  |  |
|  |  |  |  |  | 358 | 61011LF00-012-G |  | RES,499KOhm,+/-1%,1/16W,G,SMD0402 | WALSIN TECHNOLOGY CORPORATION | WR04X4993FTL |  | G |  |  |  |  |  |  |  |
|  |  |  |  |  | 358 | 61011LF00-011-G |  | RES,499KOhm,+/-1%,1/16W,G,SMD0402 | YAGEO CORPORATION COMPONENT | RC0402FR-07499KL |  | G |  |  |  |  |  |  |  |
|  |  |  |  |  | 358 | 61011LF00-044-G |  | RES,499KOhm,+/-1%,1/16W,G,SMD0402 | TA-I TECHNOLOGY CO., LTD | RM04FTN4993 |  | G |  |  |  |  |  |  |  |
| Multi | ND | ND | Y(4) | 359 | 359 | 61011HC00-017-G | - | RES,2.7KOhm,+/-1%,1/16W,G,SMD0402 | KOA SPEER ELECTRONICS, INC. | RK73H1ETTP2701F | 1 | G | R1754 |  |  |  |  |  |  |
|  |  |  |  |  | 359 | 61011HC00-012-G |  | RES,2.7KOhm,+/-1%,1/16W,G,SMD0402 | WALSIN TECHNOLOGY CORPORATION | WR04X2701FTL |  | G |  |  |  |  |  |  |  |
|  |  |  |  |  | 359 | 61011HC00-011-G |  | RES,2.7KOhm,+/-1%,1/16W,G,SMD0402 | YAGEO CORPORATION COMPONENT | RC0402FR-072K7L |  | G |  |  |  |  |  |  |  |
|  |  |  |  |  | 359 | 61011HC00-044-G |  | RES,2.7KOhm,+/-1%,1/16W,G,SMD0402 | TA-I TECHNOLOGY CO., LTD | RM04FTN2701 |  | G |  |  |  |  |  |  |  |
|  |  |  |  |  | 359 | 61011HC00-029-G |  | RES,2.7KOhm,+/-1%,1/16W,G,SMD0402 | VISHAY ENTER TECHNO LOGY.INC | CRCW04022K70FKED |  | G |  |  |  |  |  |  |  |
|  |  |  |  |  | 359 | 61011HC00-024-G |  | RES,2.7KOhm,+/-1%,1/16W,G,SMD0402 | PANASONIC INDUSTRIAL CO.,LTD. | ERJ2RKF2701X |  | G |  |  |  |  |  |  |  |
| Multi | ND | ND | Y(4) | 360 | 360 | 61010KR00-017-G | - | RES,4.99 Ohm,+/-1%,1/10W,G,SMD0603 | KOA SPEER ELECTRONICS, INC. | RK73H1JTTD4R99F | 1 | G | R1756 |  |  |  |  |  |  |
|  |  |  |  |  | 360 | 61010KR00-011-G |  | RES,4.99 Ohm,+/-1%,1/10W,G,SMD0603 | YAGEO CORPORATION COMPONENT | RC0603FR-074R99L |  | G |  |  |  |  |  |  |  |
|  |  |  |  |  | 360 | 61010KR00-044-G |  | RES,4.99 Ohm,+/-1%,1/10W,G,SMD0603 | TA-I TECHNOLOGY CO., LTD | RM06FTN4R99 |  | G |  |  |  |  |  |  |  |
| Multi | ND |  | Y(4) | 361 | 361 | 610130300-017-G |  | RES,60.4 Ohm,+/-1%,1/20W,G,SMD0201 | KOA SPEER ELECTRONICS, INC. | RK73H1HTTC60R4F | 2 | G | R1769,R1770 |  |  |  |  |  |  |
|  |  |  |  |  | 361 | 610130300-044-G |  | RES,thick film,60.4Ohm,+/-1%,1/20W,SMD0201,G | TA-I TECHNOLOGY CO., LTD | RM02FTN60R4 |  | G |  |  |  |  |  |  |  |
|  |  |  |  |  | 361 | 610130300-011-G |  | RES,thick film,60.4Ohm,+/-1%,1/20W,SMD0201,G | YAGEO CORPORATION COMPONENT | RC0201FR-0760R4L |  | G |  |  |  |  |  |  |  |
|  |  |  |  |  | 361 | 610130300-012-G |  | RES,thick film,60.4Ohm,+/-1%,1/20W,SMD0201,G | WALSIN TECHNOLOGY CORPORATION | WR02X60R4FAL |  | G |  |  |  |  |  |  |  |
|  |  |  |  |  | 361 | 610130300-029-G |  | RES,60.4 Ohm,+/-1%,1/20W,G,SMD0201 | VISHAY ENTER TECHNO LOGY.INC | CRCW020160R4FKED |  | G |  |  |  |  |  |  |  |
|  |  |  |  |  | 361 | 610130300-024-G |  | RES,60.4 Ohm,+/-1%,1/20W,G,SMD0201 | PANASONIC INDUSTRIAL CO.,LTD. | ERJ1GNF60R4C |  | G |  |  |  |  |  |  |  |
| Single | Y | ND | N | 362 | 362 | 41050W700-46Y-G | - | Flash,AT45DB081E-SHNHC-T,1.65~3.6V,8M,SPI,G,SOIC-8,SMD | Adesto Technologies Corporation | AT45DB081E-SHNHC-T | 1 | G | U_LOM1_ROM1 |  |  |  |  |  |  |
| Multi | N | other | Y(1) | 363 | 363 | 320403K00-183-G | - | IC,Temp Sensor,TMP75AIDR,3°C,G,SOIC-8,SMD | TEXAS INSTRUMENTS | TMP75AIDR | 1 | G | U_TMP |  |  |  |  |  |  |
|  |  |  |  |  | 363 | 320403Q00-173-G |  | IC,Temp Sensor,DS75S+T&R,3°C,G,SO-8,SMD | MAXIM INTEGRATED PRODUCTS, INC. | DS75S+T&R |  | G |  |  |  |  |  |  |  |
|  |  |  |  |  | 363 | 320405300-214-G |  | IC,Temp Sensor,STLM75M2F,±0.5°C,G,SO-8,SMD | ST MICRO ELECTRONICS,INC | STLM75M2F |  | G |  |  |  |  |  |  |  |
|  |  |  |  |  | 363 | 32040SL00-223-G |  | IC,Temperature Sensor,NCT75DR2G,G,SOIC-8,SMD | ON SEMICONDUCTOR CORP | NCT75DR2G |  | G |  |  |  |  |  |  |  |
|  |  |  |  |  | 363 | PCT2075D |  | IC,Temperature Sensor,PCT2075D,SO-8,SMD | NXP SEMICONDUCTORS | PCT2075D |  | G |  |  |  |  |  |  |  |
| Multi | ND |  | N | 364 | 364 | 31050KS00-185-G |  | IC,Buffer,NC7SV17P5X,0.9V~3.6V,G,SC70-5,SMD | FAIRCHILD SEMICONDUCTOR CORP | NC7SV17P5X | 2 | G | U2,U11 |  |  |  |  |  |  |
|  |  |  |  |  | 364 | 310507P00-031-G |  | Logic IC,Buffer,74AUP1G17GW,0.8V~3.6V,19ns,TSSOP,5P,G | NXP SEMICONDUCTORS | 74AUP1G17GW |  | G |  |  |  |  |  |  |  |
| Single | ND |  | Y(1) | 365 | 365 | 320242G00-183-G |  | IC,Power Controller,LM3880MFX-1AA/NOPB,G,SOT-23-6,SMD | TEXAS INSTRUMENTS | LM3880MFX-1AA/NOPB | 2 | G | U3,U4 |  |  |  |  |  |  |
| Multi | ND | ND | Y(3) | 366 | 366 | 310502800-031-G |  | IC,Buffer,74LVC1G07GW,1.65~5.5V,G,SOT353-5,SMD | NXP SEMICONDUCTORS | 74LVC1G07GW | 26 | G | U6,U7,U8,U9,U53,U54,U56,U57,U58,U59,U64,U65,U67,U69,U70,U71,U72,U85,U88,U103,U111,U113,U114,U115,U117,U169 |  |  |  |  |  |  |
|  |  |  |  |  | 366 | 31050CU00-131-G |  | IC,Buffer,TC7SZ07FU,1.65~5.5V,G,SSOP-5,SMD | TOSHIBA ELECTRONICS ASIA LTD | TC7SZ07FU |  | G |  |  |  |  |  |  |  |
|  |  |  |  |  | 366 | 310502C00-223-G |  | IC,Buffer,NL17SZ07DFT2G,1.65~5.50V,G,SC-88A/SOT-353-5,SMD | ON SEMICONDUCTOR CORP | NL17SZ07DFT2G |  | G |  |  |  |  |  |  |  |
| Single | ND |  | N | 367 | 367 | 310406Q00-031-G |  | IC,Multiplexer,CBTL01023GM,3V~3.6V,G,XQFN-10,SMD | NXP SEMICONDUCTORS | CBTL01023GM | 1 | G | U12 |  |  |  |  |  |  |
| Single | Y | ND | Y(1) | 368 | 368 | 21040M500-283-G | - | IC,BROADCOM,BCM54612EB1KMLG,B1,G,MLP-48,SMD | BROADCOM SINGAPORE PTE LTD. | BCM54612EB1KMLG | 1 | G | U13 |  |  |  |  |  |  |
| Single | ND |  | N | 369 | 369 | 21012NJ00-687-G | - | IC,ASPEED,AST2500A2-GP,A2,G,TFBGA-456,SMD | ASPEED TECHNOLOGY INC | AST2500A2-GP | 1 | G | U14 |  |  |  |  |  |  |
| Multi | ND | ND | Y(2) | 370 | 370 | 31030CA00-031-G |  | IC,Switch,PCA9546APW,2.3~5.5V,G,TSSOP-16,SMD | NXP SEMICONDUCTORS | PCA9546APW | 2 | G | U15,U16 |  |  |  |  |  |  |
|  |  |  |  |  | 370 | 31030YF00-252-G |  | Logic IC,Switch,PI4MSD5V9546ALEX,1.65V~5.5V,0.3ns,TSSOP,16P,G | PERICOM SEMICONDUCTOR CORP | PI4MSD5V9546ALEX |  | G |  |  |  |  |  |  |  |
| Multi | ND |  | Y(1) | 371 | 371 | 420212A00-216-G |  | DRAM,MT40A512M16JY-083E:B,1.2V,512M*16,1.2GHz,G,FBGA-96,SMD | MICRON SEMICONDUCTOR ASIA PTE.LTD. | MT40A512M16JY-083E:B | 1 | G | U17 |  |  |  |  |  |  |
|  |  |  |  |  | 371 | 420214J00-220-G |  | DRAM,H5AN8G6NAFR-UHC,1.2V,8G,1.2GHz,G,FBGA-96,SMD | HYNIX SEMICONDUCTOR INC | H5AN8G6NAFR-UHC |  | G |  |  |  |  |  |  |  |
| Single | N |  | Y(1) | 372 | 372 | 310311G00-183-G |  | IC,Switch,TS3L110RGYR,3V~3.6V,G,VQFN-16,SMD | TEXAS INSTRUMENTS | TS3L110RGYR | 2 | G | U18,U19 |  |  |  |  |  |  |
| Single | ND |  | N | 373 | 373 | 410512F00-233-G |  | Flash,MX66L51235FMI-10G,2.7V~3.6V,512M,SPI,G,SOP-16,SMD | MACRONIX INTERNATIONAL CO.,LTD. | MX66L51235FMI-10G | 3 | G | U20,U21,U24 |  |  |  |  |  |  |
| Multi | ND |  | N | 374 | 374 | 310312S00-217-G |  | IC,Switch,74CBTLV3125QG8,2.3V~3.6V,G,QSOP-16,SMD | INTEGRATED DEVICE TECHNOLOGY | 74CBTLV3125QG8 | 2 | G | U25,U179 |  |  |  |  |  |  |
|  |  |  |  |  | 374 | 310305U00-252-G |  | Logic IC,Switch,PI3B3125QEX,3.0V~3.6V,0.25ns,QSOP,16P,G | PERICOM SEMICONDUCTOR CORP | PI3B3125QEX |  | G |  |  |  |  |  |  |  |
| Multi | ND | ND | N | 375 | 375 | 310408900-217-G | - | IC,Switch,74CBTLV3257PGG8,2.3~3.6V,G,TSSOP-16,SMD | INTEGRATED DEVICE TECHNOLOGY | 74CBTLV3257PGG8 | 1 | G | U27 |  |  |  |  |  |  |
|  |  |  |  |  | 375 | 310405F00-252-G |  | Logic IC,Multiplexer,PI3B3257LEX,2.97V~3.63V,0.25ns,TSSOP,16P,G | PERICOM SEMICONDUCTOR CORP | PI3B3257LEX |  | G |  |  |  |  |  |  |  |
| Multi | N | ND | Y(1) | 376 | 376 | 21050F900-217-G |  | IC,IDT,2305B-1DCG8,B,G,SOIC-8,SMD | INTEGRATED DEVICE TECHNOLOGY | 2305B-1DCG8 | 1 | G | U29 |  |  |  |  |  |  |
|  |  |  |  |  | 376 | 31050JC00-223-G |  | Logic IC,Buffer,NB2305AI1DR2G,3.0V~3.6V,0.35ns,SOIC,8P,G | ON SEMICONDUCTOR CORP | NB2305AI1DR2G |  | G |  |  |  |  |  |  |  |
| Multi | N | 1 | Y(3) | 377 | 377 | 41040BT00-191-G |  | EEPROM,AT24C64D-SSHM-T,1.7~5.5V,64K,I2C,G,SOIC-8,SMD | ATMEL CORPORATION | AT24C64D-SSHM-T | 1 | G | U30 |  |  |  |  |  |  |
|  |  |  |  |  | 377 | 410405H00-214-G |  | EEPROM,M24C64-RMN6TP,1.8~5.5V,64K,I2C,G,SO-8,SMD | ST MICRO ELECTRONICS,INC | M24C64-RMN6TP |  | G |  |  |  |  |  |  |  |
|  |  |  |  |  | 377 | 410409E00-223-G |  | EEPROM,CAT24C64WI-GT3,1.8~5.5V,64K,I2C,G,SOIC-8,SMD | ON SEMICONDUCTOR CORP | CAT24C64WI-GT3 |  | G |  |  |  |  |  |  |  |
| Single | ND | ND | Y(2) | 378 | 378 | 310504D00-031-G | - | IC,Buffer,74LVC2G125DP,1.65~5.5V,G,TSSOP-8,SMD | NXP SEMICONDUCTORS | 74LVC2G125DP | 1 | G | U31 |  |  |  |  |  |  |
| Multi | N | 1 | N | 379 | 379 | 320501P00-173-G | DN644 | IC,Driver/Receiver,MAX3243CAI+T,G,SSOP-28,SMD | MAXIM INTEGRATED PRODUCTS, INC. | MAX3243CAI+T | 1 | G | U32 |  |  |  |  |  |  |
|  |  |  |  |  | 379 | 320503B00-214-G |  | IC,Driver/Receiver,ST3243ECTR-E,G,TSSOP-28,SMD | ST MICRO ELECTRONICS,INC | ST3243ECTR-E |  | G |  |  |  |  |  |  |  |
| Single | ND | ND | N | 380 | 380 | 32022AL00-223-G | - | IC,Power Controller,NCP380HSNAJAAT1G,G,TSOP-6,SMD | ON SEMICONDUCTOR CORP | NCP380HSNAJAAT1G | 3 | G | U33,U35,U177 |  |  |  |  |  |  |
| Single | ND |  | N | 381 | 381 | 21081AQ00-426-G |  | IC,RENESAS,uPD720201K8-701-BAC-A,G,QFN-68,SMD | RENESAS TECHNOLOGY AMERICA INC | uPD720201K8-701-BAC-A | 1 | G | U36 |  |  |  |  |  |  |
| Single | ND | ND | N | 382 | 382 | 41050J100-233-G | - | Flash,MX25L5121EMC-20G,2.7~3.6V,512K,SPI,G,SOP-8,SMD | MACRONIX INTERNATIONAL CO.,LTD. | MX25L5121EMC-20G | 1 | G | U37 |  |  |  |  |  |  |
| Single | ND |  | N | 383 | 383 | 210826400-183-G |  | IC,TI,TUSB2077APTR,G,LQFP-48,SMD | TEXAS INSTRUMENTS | TUSB2077APTR | 1 | G | U38 |  |  |  |  |  |  |
| Single | ND |  | N | 384 | 384 | 21081N000-348-G |  | IC,MARVELL,88SE9235A1-NAA2C000,A1,G,QFN-76,SMD | MARVELL SEMICONDUCTOR, INC | 88SE9235A1-NAA2C000[VER.A1] | 1 | G | U45 |  |  |  |  |  |  |
| Multi | ND | ND | N | 385 | 385 | 41050K700-233-G | - | Flash,MX25L4006EM2I-12G,2.7V~3.6V,4M,SPI,G,SOP-8,SMD | MACRONIX INTERNATIONAL CO.,LTD. | MX25L4006EM2I-12G | 1 | G | U46 |  |  |  |  |  |  |
|  |  |  |  |  | 385 | 41050RL00-205-G |  | NOR Flash,W25X40CLSSIG,2.3V,N/A,3.6V,4M,SPI,-40_x0003_~85_x0003_,SOIC,8P,G | WINBOND ELECTRONIC CO.,LTD. | W25X40CLSSIG |  | G |  |  |  |  |  |  |  |
| Multi | ND | ND | Y(3) | 386 | 386 | 310203000-031-G |  | IC,Trigger,74LVC74APW,1.2~3.6V,G,TSSOP-14,SMD | NXP SEMICONDUCTORS | 74LVC74APW | 2 | G | U55,U168 |  |  |  |  |  |  |
|  |  |  |  |  | 386 | 310202400-223-G |  | IC,Trigger,MC74LCX74DTR2G,2.3~3.6V,G,TSSOP-14,SMD | ON SEMICONDUCTOR CORP | MC74LCX74DTR2G |  | G |  |  |  |  |  |  |  |
|  |  |  |  |  | 386 | 310208S00-131-G |  | IC,Trigger,74LCX74FT,1.65V~3.6V,G,TSSOP-14,SMD | TOSHIBA ELECTRONICS ASIA LTD | 74LCX74FT |  | G |  |  |  |  |  |  |  |
| Single | Y |  | N | 387 | 387 | PCF8523TK/1 |  | IC,NXP,PCF8523TK/1,G,HVSON-8,SMD | NXP SEMICONDUCTORS | PCF8523TK/1 | 1 | G | U60 |  |  |  |  |  |  |
| Multi | ND |  | N | 388 | 388 | 21050Q600-217-G |  | IC,IDT,5PB1102PGGI8,G,TSSOP-8,SMD | INTEGRATED DEVICE TECHNOLOGY | 5PB1102PGGI8 | 1 | G | U61 |  |  |  |  |  |  |
|  |  |  |  |  | 388 | 31050JY00-223-G |  | Logic IC,Buffer,NB3V1102CDTR2G,1.8V/2.5V/3.3V,3.5ns,TSSOP,8P,G | ON SEMICONDUCTOR CORP | NB3V1102CDTR2G |  | G |  |  |  |  |  |  |  |
| Single | ND | ND | N | 389 | 389 | 21050R500-298-G |  | IC,SILABS,Si5338C-B06799-GMR,G,QFN-24,SMD | Silicon Laboratories Inc. | SI5338C-B06799-GMR | 1 | G | U62 |  |  |  |  |  |  |
| Single | ND |  | Y(1) | 390 | 390 | 21050P100-217-G |  | IC,IDT,9DBL0452BKILFT,G,VFQFPN-32,SMD | INTEGRATED DEVICE TECHNOLOGY | 9DBL0452BKILFT | 1 | G | U63 |  |  |  |  |  |  |
| Multi | N | ND | Y(3) | 391 | 391 | 310101400-031-G | - | IC,Gate&Inverter,74LVC1G08GW,1.65~5.5V,G,SOT353-5,SMD | NXP SEMICONDUCTORS | 74LVC1G08GW | 13 | G | U66,U73,U74,U75,U76,U77,U78,U79,U80,U81,U82,U161,U178 |  |  |  |  |  |  |
|  |  |  |  |  | 391 | 310103J00-223-G |  | IC,Gate&Inverter,NL17SZ08DFT2G,1.65~5.5V,G,SOT353-5,SMD | ON SEMICONDUCTOR CORP | NL17SZ08DFT2G |  | G |  |  |  |  |  |  |  |
|  |  |  |  |  | 391 | 31010J400-131-G |  | IC,Gate&Inverter,TC7SZ08FU,1.8~5.5V,G,SSOP-5,SMD | TOSHIBA ELECTRONICS ASIA LTD | TC7SZ08FU |  | G |  |  |  |  |  |  |  |
| Multi | ND |  | N | 392 | 392 | 310504B00-031-G |  | IC,Buffer,74LVC1G17GW,1.65~5.5V,G,SOT353-5,SMD | NXP SEMICONDUCTORS | 74LVC1G17GW | 3 | G | U68,U86,U89 |  |  |  |  |  |  |
|  |  |  |  |  | 392 | 310507Q00-223-G |  | Logic IC,Buffer,NL17SZ17DFT2G,1.65V~5.5V,15ns,SC-88A/SOT-353,5P,G | ON SEMICONDUCTOR CORP | NL17SZ17DFT2G |  | G |  |  |  |  |  |  |  |
|  |  |  |  |  | 392 | 31050BH00-131-G |  | IC,Buffer,TC7SZ17FU,1.65~5.5V,G,SSOP-5,SMD | TOSHIBA ELECTRONICS ASIA LTD | TC7SZ17FU |  | G |  |  |  |  |  |  |  |
| Multi | ND | ND | Y(3) | 393 | 393 | 310500F00-031-G | - | IC,Buffer,74LVC07APW,1.65~5.5V,G,TSSOP-14,SMD | NXP SEMICONDUCTORS | 74LVC07APW | 3 | G | U83,U101,U102 |  |  |  |  |  |  |
|  |  |  |  |  | 393 | 31050LF00-237-G |  | IC,Buffer,74LVC07AT14-13,1.65V~5.5V,G,TSSOP-14,SMD | DIODES INCORPORATION | 74LVC07AT14-13 |  | G |  |  |  |  |  |  |  |
| Single | ND |  | Y(1) | 394 | 394 | 320231500-183-G |  | IC,Voltage Sensor,TPS3897ADRYR,G,SON-6,SMD | TEXAS INSTRUMENTS | TPS3897ADRYR | 1 | G | U84 |  |  |  |  |  |  |
| Single | ND |  | Y(1) | 395 | 395 | 32020LS00-183-G |  | IC,Power Controller,TPS3801K33DCKR,G,SC-70-5,SMD | TEXAS INSTRUMENTS | TPS3801K33DCKR | 1 | G | U87 |  |  |  |  |  |  |
| Multi | Y | 1 | Y(3) | 396 | 396 | 310201900-031-G | - | IC,Gate&Inverter,74LVC2G14GW,1.65~5.5V,G,SOT363-6,SMD | NXP SEMICONDUCTORS | 74LVC2G14GW | 3 | G | U90,U91,U112 |  |  |  |  |  |  |
|  |  |  |  |  | 396 | 310203300-223-G |  | Logic IC,Trigger,NL27WZ14DFT2G,1.65V~5.5V,7.4ns,SC-70/SOT-323,6P,G | ON SEMICONDUCTOR CORP | NL27WZ14DFT2G |  | G |  |  |  |  |  |  |  |
| Single | ND |  | Y(3) | 397 | 397 | 31050J800-031-G |  | IC,Buffer,PCA9516APW,2.3V~3.6V,G,TSSOP-16,SMD | NXP SEMICONDUCTORS | PCA9516APW | 4 | G | U92,U93,U94,U95 |  |  |  |  |  |  |
| Single | N |  | Y(2) | 398 | 398 | 32021R100-252-G |  | IC,Power Controller,PI3USB102ZLEX,G,TQFN-10P,SMD | PERICOM SEMICONDUCTOR CORP | PI3USB102ZLEX | 2 | G | U96,U108 |  |  |  |  |  |  |
| Single | ND |  | Y(2) | 399 | 399 | 31090C800-031-G |  | IC,Transceiver,74AVC4TD245GU,0.8V~3.6V,G,XQFN-16,SMD | NXP SEMICONDUCTORS | 74AVC4TD245GU | 1 | G | U97 |  |  |  |  |  |  |
| Multi | ND | ND | Y(1) | 400 | 400 | 410403P00-214-G | - | EEPROM,M24512-WMN6TP,2.5~5.5V,512K,I2C,G,SO-8,SMD | ST MICRO ELECTRONICS,INC | M24512-WMN6TP | 1 | G | U98 |  |  |  |  |  |  |
|  |  |  |  |  | 400 | 410406K00-214-G |  | EEP Memory,M24512-RMN6TP,1.8V,N/A,5.5V,512K,I2C,-40_x0003_~85_x0003_,SO,8P,G | ST MICRO ELECTRONICS,INC | M24512-RMN6TP |  | G |  |  |  |  |  |  |  |
|  |  |  |  |  | 400 | 41040D200-191-G |  | EEP Memory,AT24C512C-SSHM-T,1.7V,N/A,3.6V,512K,I2C,-40_x0003_~85_x0003_,SOIC,8P,G | ATMEL CORPORATION | AT24C512C-SSHM-T |  | G |  |  |  |  |  |  |  |
| Single | ND | ND | Y(2) | 401 | 401 | 210203M00-031-G | - | IC,NXP,PCA9554PW,G,TSSOP-16,SMD | NXP SEMICONDUCTORS | PCA9554PW | 2 | G | U99,U100 |  |  |  |  |  |  |
| Multi | ND |  | N | 402 | 402 | 311004800-031-G |  | IC,Translator,PCA9617ADPJ,0.8~5.5V,2.2~5.5V,G,TSSOP-8,SMD | NXP SEMICONDUCTORS | PCA9617ADPJ | 4 | G | U104,U105,U106,U107 |  |  |  |  |  |  |
|  |  |  |  |  | 402 | 311004V00-223-G |  | Logic IC,Translator,PCA9617ADMR2G,Vcca=0.8V~5.5V,Vccb=2.2V~5.5V,102ns,Micro8,8P,G | ON SEMICONDUCTOR CORP | PCA9617ADMR2G |  | G |  |  |  |  |  |  |  |
| Multi | ND |  | Y(2) | 403 | 403 | 310307T00-031-G |  | IC,Switch,74CBTLV1G125GV,2.3~3.6V,G,SOT753-5,SMD | NXP SEMICONDUCTORS | 74CBTLV1G125GV | 1 | G | U109 |  |  |  |  |  |  |
|  |  |  |  |  | 403 | 310300D00-183-G |  | IC,Switch,SN74CBTLV1G125DBVR,2.3~3.6V,G,SOT23-5,SMD | TEXAS INSTRUMENTS | SN74CBTLV1G125DBVR |  | G |  |  |  |  |  |  |  |
| Multi | ND |  | N | 404 | 404 | 330103N00-426-G |  | IC,Optocoupler,PS2811-1-F3-A,G,SSOP-4,SMD | RENESAS TECHNOLOGY AMERICA INC | PS2811-1-F3-A | 1 | G | U110 |  |  |  |  |  |  |
|  |  |  |  |  | 404 | 330102900-289-G |  | OPTO-IC,ISOL,LTV-217-G,SSOP,4P,G | LITE-ON TECHNOLOGY CORPORATION | LTV-217-G |  | G |  |  |  |  |  |  |  |
|  |  |  |  |  | 404 | 330103T00-029-G |  | IC,Optocoupler,VOS618A-3X001T,G,SSOP-4,SMD | VISHAY ENTER TECHNO LOGY.INC | VOS618A-3X001T |  | G |  |  |  |  |  |  |  |
| Single | ND |  | N | 405 | 405 | 21081WR00-031-G |  | IC,NXP,PCA9541APW/01,G,TSSOP-16,SMD | NXP SEMICONDUCTORS | PCA9541APW/01 | 1 | G | U116 |  |  |  |  |  |  |
| Single | ND |  | Y(1) | 406 | 406 | 311006F00-031-G |  | IC,Translator,PCA9508D,0.9V~5.5V/2.7V~5.5V,G,SO-8,SMD | NXP SEMICONDUCTORS | PCA9508D | 1 | G | U164 |  |  |  |  |  |  |
| Single | ND |  | N | 407 | 407 | 320242H00-226-G |  | IC,Power Controller,LTC2955CDDB-2#TRMPBF,G,DFN-10,SMD | LINEAR TECHNOLOGY CORPORATION | LTC2955CDDB-2#TRMPBF | 1 | G | U165 |  |  |  |  |  |  |
| Single | ND |  | N | 408 | 408 | 32050Q900-031-G |  | IC,LED Driver,PCA9551PW,G,TSSOP-16,SMD | NXP SEMICONDUCTORS | PCA9551PW | 2 | G | U166,U172 |  |  |  |  |  |  |
| Multi | N | Other | Y(4) | 409 | 409 | 310203U00-223-G |  | IC,Trigger,NL17SZ14DFT2G,1.65~5.5V,G,SOT353-5,SMD | ON SEMICONDUCTOR CORP | NL17SZ14DFT2G | 2 | G | U167,U173 |  |  |  |  |  |  |
|  |  |  |  |  | 409 | 310200900-185-G |  | IC,Trigger,NC7SZ14P5X,1.65-5.5V,G,SC70-5P,SMD | FAIRCHILD SEMICONDUCTOR CORP | NC7SZ14P5X |  | G |  |  |  |  |  |  |  |
|  |  |  |  |  | 409 | 310107000-031-G |  | Logic IC,Gate&Inverter,74LVC1G14GW,1.65V~5.5V,14ns,TSSOP,5P,G | NXP SEMICONDUCTORS | 74LVC1G14GW |  | G |  |  |  |  |  |  |  |
| Multi | ND | ND | Y(3) | 410 | 410 | 310109D00-031-G | - | IC,Gate&Inverter,74LVC1G32GW,1.65~5.5V,G,TSSOP-5,SMD | NXP SEMICONDUCTORS | 74LVC1G32GW | 3 | G | U170,U174,U180 |  |  |  |  |  |  |
|  |  |  |  |  | 410 | 310109E00-223-G |  | IC,Gate&Inverter,NL17SZ32DFT2G,1.65~5.5V,G,SOT-353-5,SMD | ON SEMICONDUCTOR CORP | NL17SZ32DFT2G |  | G |  |  |  |  |  |  |  |
|  |  |  |  |  | 410 | 31010VY00-131-G |  | IC,Gate&Inverter,TC7SZ32FU,1.65~5.5V,G,SSOP-5,SMD | TOSHIBA ELECTRONICS ASIA LTD | TC7SZ32FU,LJ(CT |  | G |  |  |  |  |  |  |  |
| Multi | ND |  | Y(3) | 411 | 411 | 31050KL00-031-G |  | IC,Buffer,74HC75PW,2.0V~6.0V,G,TSSOP-16,SMD | NXP SEMICONDUCTORS | 74HC75PW | 1 | G | U171 |  |  |  |  |  |  |
|  |  |  |  |  | 411 | 311007400-183-G |  | IC,Translator,CD74HC75PWRG4,2V~6V,G,TSSOP-16,SMD | TEXAS INSTRUMENTS | CD74HC75PWRG4 |  | G |  |  |  |  |  |  |  |
| Single | ND |  | Y(1) | 412 | 412 | 31010SB00-183-G |  | Logic IC,Gate,ISO1540DR,3V~5.5V,G,SOIC-8,SMD | TEXAS INSTRUMENTS | ISO1540DR | 1 | G | U175 |  |  |  |  |  |  |
| Multi | ND |  | N | 413 | 413 | 71011RD00-100-G |  | XTAL,25MHz,+/-25ppm,20pF,G,SMD | TXC CORPORATION | 7V25000016 | 1 | G | X1 |  |  |  |  |  |  |
|  |  |  |  |  | 413 | 71012KY00-107-G |  | XTAL,25MHz,+/-25ppm,20pF,G,SMD | DAISHINKU CORPORATION/DAISHINKU SINGAPORE PTE LTD/KDS | 1N225000CC0DT |  | G |  |  |  |  |  |  |  |
| Multi | ND | ND | N | 414 | 414 | 71010SY00-107-G |  | XTAL,25MHz,+/-30ppm,20pF,G,SMD | DAISHINKU CORPORATION/DAISHINKU SINGAPORE PTE LTD/KDS | 1Y725000CC1G | 1 | G | X2 |  |  |  |  |  |  |
|  |  |  |  |  | 414 | 71012JL00-873-G |  | XTAL,25MHz,+/-30ppm,20pF,G,SMD-2P | KYOCERA ELCO CORPORATION | CX5032GA25000R0KDQZ1 |  | G |  |  |  |  |  |  |  |
| Multi | ND |  | N | 415 | 415 | 710113800-100-G |  | XTAL,24MHz,+/-30ppm,20pF,G,SMD | TXC CORPORATION | 7B24000038 | 1 | G | X3 |  |  |  |  |  |  |
|  |  |  |  |  | 415 | 71012JK00-873-G |  | XTAL,24MHz,+/-30ppm,20pF,G,SMD | KYOCERA ELCO CORPORATION | CX5032SB24000R0KZQ01 |  | G |  |  |  |  |  |  |  |
| Single | ND |  | N | 416 | 416 | 71012EC00-162-G |  | XTAL,6MHz,+/-30ppm,20pF,G,SMD | EPSON ELECTRONICS AMERICA,INC. | Q22MA4061164200 | 1 | G | X4 |  |  |  |  |  |  |
| Single | ND |  | N | 417 | 417 | 71011UL00-107-G |  | XTAL,25MHz,+/-15ppm,16pF,G,SMD | DAISHINKU CORPORATION/DAISHINKU SINGAPORE PTE LTD/KDS | 1ZHY25000BB0A | 1 | G | X5 |  |  |  |  |  |  |
| Multi | ND |  | Y(1) | 418 | 418 | 710106900-162-G |  | XTAL,32.768KHz,+/-20ppm,12.5pF,G,SMD | EPSON ELECTRONICS AMERICA,INC. | Q13FC1350000400 | 1 | G | X6 |  |  |  |  |  |  |
|  |  |  |  |  | 418 | 710110M00-873-G |  | XTAL,32.768KHz,+/-20ppm,12.5pF,G,SMD | KYOCERA ELCO CORPORATION | ST3215SB32768H5HPWAA |  | G |  |  |  |  |  |  |  |
|  |  |  |  |  | 418 | 710123400-061-G |  | XTAL,32.768KHz,+/-20ppm,12.5pF,-40_x0003_~85_x0003_,SMD,G | TAITIEN ELECTRONICS CO.,LTD | 06172-W-052-3 |  | G |  |  |  |  |  |  |  |
| Multi | ND |  | N | 419 | 419 | 71020SC00-107-G |  | OSC,24MHz,+/-25ppm,3.3V,15pF,G,SMD | DAISHINKU CORPORATION/DAISHINKU SINGAPORE PTE LTD/KDS | 1XSE024000AR40 | 1 | G | Y1 |  |  |  |  |  |  |
|  |  |  |  |  | 419 | 710217200-16G-G |  | OSC,24MHz,+/-25ppm,3.3V,15pF,G,SMD | SiTime Corporation | SIT1602BI-22-33E-24.000000 |  | G |  |  |  |  |  |  |  |
| Multi | N |  | N | 420 | 420 | 71020Q600-16G-G |  | OSC,50MHz,50ppm,3.3V,G,SMD | SiTime Corporation | SIT1602AC-23-33E-50.000000T | 1 | G | Y2 |  |  |  |  |  |  |
|  |  |  |  |  | 420 | 71012DA00-100-G |  | OSC,50MHz,+/-25ppm,15pF,G,SMD | TXC CORPORATION | 7X50000015 |  | G |  |  |  |  |  |  |  |
|  |  |  |  |  | 420 | 710216Q00-098-G |  | OSC,50MHz,50ppm,3.3V,G,SMD | HARMONY (HELE) | SSW050000I3CHE-ST7R2 |  | G |  |  |  |  |  |  |  |
|  |  |  |  |  | 420 | 710216P00-873-G |  | OSC,50MHz,50ppm,3.3V,G,SMD | KYOCERA ELCO CORPORATION | KC3225K50.0000C1GE00 |  | G |  |  |  |  |  |  |  |
| Single | ND |  | N | 421 | 421 | 710213J00-16G-G |  | OSC,25MHz,+/-1.5ppm,3.3V,15pF,G,SMD | SiTime Corporation | SIT5000AC-3B-33N0-25.000000T | 1 | G | Y3 |  |  |  |  |  |  |
| Multi | ND | ND | Y(1) | 422 | 422 | 71020KL00-100-G | - | OSC,33MHz,+/-50ppm,3.3V,15pF,G,SMD | TXC CORPORATION | 7X33000013 | 1 | G | Y4 |  |  |  |  |  |  |
|  |  |  |  |  | 422 | 710211800-967-G |  | OSC,33MHz,+/-50ppm,3.3V,15pF,G,SMD | SaRonix-eCERA Corporation | FK3300011 |  | G |  |  |  |  |  |  |  |
|  |  |  |  |  | 422 | 710216N00-873-G |  | OSC,33MHz,+/-50ppm,3.3V,15pF,G,SMD | KYOCERA ELCO CORPORATION | KC3225K33.0000C10E00 |  | G |  |  |  |  |  |  |  |
| Single | Y |  | N | 423 | 423 | 340660600-GRS-G |  | CONN,Header,Battery Holder,Bla,21.3mm,G/F,G,SMD-2 | LOTES CO LTD | AAA-BAT-063-P02_A | 1 | G | B1 |  |  |  |  |  |  |
| Single | ND | ND | N | 424 | 424 | 2T714BY00-086-G | - | Fuse Clips,10.67mm*7.11mm*7.87mm,G,LITTELFUSE,01220088Z | LITTELFUSE FAR EAST PTE LTD | 01220088Z | 4 | G | CLIP1,CLIP2,CLIP3,CLIP4 |  |  |  |  |  |  |
| Multi | ND | ND | N | 425 | 425 | 34021BC00-G78-G | - | CONN,DDR IV,V/T,1.2V,Blu,0.85mm,15u,G,SMD-288 | FCI CONNECTORS HONGKONG LTD. | 10140702-0302K11LF | 16 | G | DIMM02,DIMM04,DIMM06,DIMM09,DIMM11,DIMM13,DIMM15,DIMM16,DIMM18,DIMM20,DIMM22,DIMM25,DIMM27,DIMM29,DIMM31,DIMM00 |  |  |  |  |  |  |
|  |  |  |  |  | 425 | 34021CD00-600-G |  | Memory Connector,AH58897-T2L31-3F,DDR IV,288,SMD,THERMOPLASTIC,0.85mm,15u",Blue,G | FOXCONN TECHNOLOGY CO.,LTD. | AH58897-T2L31-3F |  | G |  |  |  |  |  |  |  |
|  |  |  |  |  | 425 | 34021E200-GRS-G |  | CONN,DDR IV,V/T,1.2V,Blu,0.85mm,15u,G,SMD-288 | LOTES CO LTD | ADDR0245-K010C |  | G |  |  |  |  |  |  |  |
|  |  |  |  |  | 425 | 34021DR00-317-G |  | CONN,DDR IV,V/T,1.2V,Blu,0.85mm,15u,G,SMD-288 | MOLEX INCORPORATED | 204245-1004 |  | G |  |  |  |  |  |  |  |
| Multi | ND | ND | N | 426 | 426 | 34021BD00-G78-G | - | CONN,DDR IV,V/T,1.2V,Bla,0.85mm,15u,G,SMD-288 | FCI CONNECTORS HONGKONG LTD. | 10140702-0301K11LF | 16 | G | DIMM01,DIMM03,DIMM05,DIMM07,DIMM08,DIMM10,DIMM12,DIMM14,DIMM17,DIMM19,DIMM21,DIMM23,DIMM24,DIMM26,DIMM28,DIMM30 |  |  |  |  |  |  |
|  |  |  |  |  | 426 | 34021E100-GRS-G |  | CONN,DDR IV,V/T,1.2V,Bla,0.85mm,15u,G,SMD-288 | LOTES CO LTD | ADDR0245-P009C |  | G |  |  |  |  |  |  |  |
|  |  |  |  |  | 426 | 34021CF00-600-G |  | Memory Connector,AH58897-T2B21-3F,DDR IV,288,SMD,THERMOPLASTIC,0.85mm,15u",Black,G | FOXCONN TECHNOLOGY CO.,LTD. | AH58897-T2B21-3F |  | G |  |  |  |  |  |  |  |
|  |  |  |  |  | 426 | 34021DS00-317-G |  | CONN,DDR IV,V/T,1.2V,Bla,0.85mm,15u,G,SMD-288 | MOLEX INCORPORATED | 204245-1003 |  | G |  |  |  |  |  |  |  |
| Multi | ND | ND | N | 427 | 427 | 340612R00-309-G | - | CONN,Jumper,Bla,2.54mm,G,DIP-2 | SAMTEC INC. | SNT-100-BK-G | 4 | G | JP1(2-3),JP4(2-3),JP5(2-3),JP6(1-2) |  |  |  |  |  |  |
|  |  |  |  |  | 427 | 34065L900-GRT-G |  | CONN,jumper,Bla,2.54mm,30u,G,DIP-2 | PINREX TECHNOLOGY CORP. | 201-71-01DB00 |  | G |  |  |  |  |  |  |  |
|  |  |  |  |  | 427 | 34066N500-600-G |  | CONN,Header,Jumper,1X2,V/T,Bla,2.54mm,G/F,G,DIP-2 | FOXCONN TECHNOLOGY CO.,LTD. | SJ0520F-A0 |  | G |  |  |  |  |  |  |  |
| Single | N | ND | N | 428 | 428 | 340692800-309-G | - | CONN,Header,Socket,2X30,V/T,Bla,0.5mm,G/F,G,SMD-60 | SAMTEC INC. | QSH-030-01-F-D-A-K-TR | 1 | G | J2 |  |  |  |  |  |  |
| Single | ND | ND | N | 429 | 429 | 3406A2A00-309-G | - | CONN,Header,Shrouded,2X4,V/T,1.27mm,15u,G,SMD-8 | SAMTEC INC. | TFM-104-02-L-D-K-TR | 1 | G | J9 |  |  |  |  |  |  |
| Multi | ND |  | N | 430 | 430 | 3406AEU00-245-G |  | CONN,Header,Shrouded,2X4,R/A,Bla,2.54mm,G/F,G,DIP-8 | AMPHENOL SHANGHAI CORP. | G821EU208AGN00Y | 1 | G | J11 |  |  |  |  |  |  |
|  |  |  |  |  | 430 | 3406AYC00-GRT-G |  | Header&Socket Connector,511-90-08GB00,Shrouded Header,8,DIP,NY9T,2.54mm,3u",Black,G | PINREX TECHNOLOGY CORP. | 511-90-08GB00 |  | G |  |  |  |  |  |  |  |
|  |  |  |  |  | 430 | 3406AYE00-637-G |  | Header&Socket Connector,3112110800-0231,Shrouded Header,8,DIP,NY6T,2.54mm,3u",Black,G | LONG SHOUNG CO.,LTD. | 3112110800-0231 |  | G |  |  |  |  |  |  |  |
| Single | ND |  | N | 431 | 431 | 3406AGV00-317-G |  | CONN,Header,WTB,2X8,V/T,Whi,1.25mm,G,SMD-16 | MOLEX INCORPORATED | 5054331671 | 1 | G | J12 |  |  |  |  |  |  |
| Single | ND |  | N | 432 | 432 | 34071AW00-245-G |  | CONN,SATA,V/T,Bla,1.27mm,15u,G,DIP-22 | AMPHENOL SHANGHAI CORP. | G16CE41210W3EU | 1 | G | J14 |  |  |  |  |  |  |
| Multi | ND | ND | N | 433 | 433 | 34031RP00-600-G | - | CONN,NGFF,R/A,Bla,0.5mm,30u,G,SMD-67 | FOXCONN TECHNOLOGY CO.,LTD. | 2E0BC23-S85BM-7H | 1 | G | J15 |  |  |  |  |  |  |
|  |  |  |  |  | 433 | 34031T300-GRS-G |  | CONN,NGFF,R/A,Bla,0.5mm,30u,G,SMD-67 | LOTES CO LTD | APCI0164-P004A |  | G |  |  |  |  |  |  |  |
| Single | ND |  | N | 434 | 434 | 34131WS00-G78-G |  | CONN,BTB,Bla,0.8mm,7.87u,G,SMD-120 | FCI CONNECTORS HONGKONG LTD. | 10139781-122402LF | 1 | G | J16 |  |  |  |  |  |  |
| Single | ND |  | N | 435 | 435 | 34131WT00-G78-G |  | CONN,BTB,Bla,0.8mm,7.87u,G,SMD-80 | FCI CONNECTORS HONGKONG LTD. | 10139781-082402LF | 2 | G | J17,J18 |  |  |  |  |  |  |
| Multi | ND |  | N | 436 | 436 | 3406AMV00-317-G |  | CONN,Header,MINFIT,2X4,V/T,Bla,10mm,30u,G,DIP-8 | MOLEX INCORPORATED | 42819-4233 | 1 | G | J27 |  |  |  |  |  |  |
|  |  |  |  |  | 436 | 3406AYH00-971-G |  | Header&Socket Connector,C23709-10433-Y,Power Connector,4,DIP,LCP,10mm,30u",Black,G | ALLTOP TECHNOLOGY CO.,LTD | C23709-10433-Y |  | G |  |  |  |  |  |  |  |
| Multi | ND |  | N | 437 | 437 | 34071BR00-245-G |  | CONN,SAS,V/T,0.6mm,30u,G,SMD-74 | AMPHENOL SHANGHAI CORP. | U10-K074-260T | 2 | G | J28,J31 |  |  |  |  |  |  |
|  |  |  |  |  | 437 | U10-K274-260T |  | CONN,SAS,V/T,0.6mm,30u,G,SMD-74 | AMPHENOL SHANGHAI CORP. | U10-K274-260T |  | G |  |  |  |  |  |  |  |
| Multi | ND |  | N | 438 | 438 | 34071BS00-245-G |  | CONN,SAS,V/T,0.6mm,30u,G,SMD-74 | AMPHENOL SHANGHAI CORP. | U10-K074-26BT | 2 | G | J30,J33 |  |  |  |  |  |  |
|  |  |  |  |  | 438 | U10-K274-26BT |  | CONN,SAS,V/T,0.6mm,30u,G,SMD-74 | AMPHENOL SHANGHAI CORP. | U10-K274-26BT |  | G |  |  |  |  |  |  |  |
| Single | ND | ND | N | 439 | 439 | 3406A9H00-309-G | - | CONN,Header,Socket,V/T,Bla,2.54mm,30u,G,SMD-12 | SAMTEC INC. | SSM-106-S-DV-P-TR | 1 | G | J34 |  |  |  |  |  |  |
| Multi | ND |  | N | 440 | 440 | 3406AQH00-317-G |  | CONN,Header,Pin Header,1X6,V/T,Bla,2.54mm,G,SMD-6 | MOLEX INCORPORATED | 87898-0656 | 5 | G | J35,J37,J39,J42,J45 |  |  |  |  |  |  |
|  |  |  |  |  | 440 | 3406BAS00-245-G |  | CONN,Header,Pin Header,1X6,V/T,Bla,2.54mm,G,SMD-6 | AMPHENOL SHANGHAI CORP. | G800MR302032HR |  | G |  |  |  |  |  |  |  |
|  |  |  |  |  | 440 | 3406A9F00-GRT-G |  | Header&Socket Connector,212-91-06GBE2,Pin Header,6,SMD,NY6T,2.54mm,3u",Black,G | PINREX TECHNOLOGY CORP. | 212-91-06GBE2 |  | G |  |  |  |  |  |  |  |
| Single | ND |  | N | 441 | 441 | 34051FE00-GRS-G |  | CONN,Modular Jack,USBX2_RJ45,R/A,Bla/Blu,2mm,30u,G,DIP-23 | LOTES CO LTD | AUSBS002-K001C05 | 1 | G | J99 |  |  |  |  |  |  |
| Multi | ND | ND | N | 442 | 442 | 34062MW00-309-G |  | CONN,Header,WTB,2X5,V/T,Bla,1.27mm,10u,G,SMD-10 | SAMTEC INC. | FTSH-105-01-L-DV-K-P-TR | 1 | G | J101 |  |  |  |  |  |  |
|  |  |  |  |  | 442 | 3406AR700-GRT-G |  | Header&Socket Connector,232-9B-05SBEC,Pin Header,10,SMD,NY6T,1.27mm,10u",Black,G | PINREX TECHNOLOGY CORP. | 232-9B-05SBEC |  | G |  |  |  |  |  |  |  |
| Single | ND |  | N | 443 | 443 | 340653G00-317-G |  | CONN,Header,Shrouded,2X11,V/T,Bla,2mm,30u,G,SMD-22 | MOLEX INCORPORATED | 87832-6023 | 1 | G | J102 |  |  |  |  |  |  |
| Single | ND |  | N | 444 | 444 | 3406ALY00-317-G |  | CONN,Header,Shrouded,2X6,V/T,Bla,2mm,30u,G,SMD-12 | MOLEX INCORPORATED | 87832-5523 | 1 | G | J103 |  |  |  |  |  |  |
| Multi | Y |  | N | 445 | 445 | 34050PV00-48U-G |  | CONN,Modular Jack,RJ45X2,R/A,Bla,1.27mm,50u,G,DIP-28 | TRP CONNECTOR B.V. | 1840855-5 | 1 | G | LAN1 |  |  |  |  |  |  |
|  |  |  |  |  | 445 | 34051E700-609-G |  | CONN,Modular Jack,RJ45X2,R/A,Bla,1.27mm,50u,G,DIP-28 | U.D. Electronic Corp. | MA-FN-0003 |  | G |  |  |  |  |  |  |  |
|  |  |  |  |  | 445 | 34050BF00-245-G |  | CONN,RJ45,Multi port,R/A,Bla,1.27mm,30u,G,DIP-28 | AMPHENOL SHANGHAI CORP. | RJMG221031470NR |  | G |  |  |  |  |  |  |  |
| Multi | ND | ND | N | 446 | 446 | 340634U00-600-G |  | CONN,Pin Header,2X3,V/T,Bla,2.54mm,30u,G,SMD-6 | FOXCONN TECHNOLOGY CO.,LTD. | HS1103H-RN | 6 | G | PBMJ1,PBEJ1,PBAJ1,PAMJ1,PAEJ1,PAAJ1 |  |  |  |  |  |  |
|  |  |  |  |  | 446 | 34068GL00-317-G |  | CONN,Header,Pin Header,2X3,V/T,Bla,2.54mm,30u,SMD-6 | MOLEX INCORPORATED | 015-91-6063 |  | G |  |  |  |  |  |  |  |
|  |  |  |  |  | 446 | 3406AY700-637-G |  | Header&Socket Connector,11006A5807,Pin Header,6,SMD,NY6T,2.54mm,30u",Black,G | LONG SHOUNG CO.,LTD. | 11006A5807 |  | G |  |  |  |  |  |  |  |
|  |  |  |  |  | 447 | 34068GJ00-GRT-G |  | CONN,Header,Pin Header,2X3,V/T,Bla,2.54mm,30u,SMD-6 | PINREX TECHNOLOGY CORP. | 212-92-03SBEL |  | G |  |  |  |  |  |  |  |
| Multi | N | ND | Y(5) | 447 | 447 | RN731ETTP5900B25 |  | RES,590Ohm,+/-0.1%,1/16W,G,SMD0402 | KOA SPEER ELECTRONICS, INC. | RN731ETTP5900B25 | 2 | G | PBAR34,PAAR34 |  |  |  |  |  |  |
|  |  |  |  |  | 447 | TNPW0402590RBEED |  | RES,590Ohm,+/-0.1%,1/16W,G,SMD0402 | VISHAY ENTER TECHNO LOGY.INC | TNPW0402590RBEED |  | G |  |  |  |  |  |  |  |
|  |  |  |  |  | 447 | ERA2AEB5900X |  | RES,590Ohm,+/-0.1%,1/16W,G,SMD0402 | PANASONIC INDUSTRIAL CO.,LTD. | ERA2AEB5900X |  | G |  |  |  |  |  |  |  |
|  |  |  |  |  | 447 | RT0402BRD07590RL |  | RES,590Ohm,+/-0.1%,1/16W,G,SMD0402 | YAGEO CORPORATION COMPONENT | RT0402BRD07590RL |  | G |  |  |  |  |  |  |  |
| Single | N |  | N | 448 | 448 | ISL68137IRAZ-GG05 |  | IC,PWM Controller,ISL68137IRAZ-T,G,QFN-48,SMD | INTERSIL CORPORATION | ISL68137IRAZ-GG05 | 8 | G | PBMU1,PBFU1,PBEU1,PBAU1,PAMU1,PAFU1,PAEU1,PAAU1 |  |  |  |  |  |  |
| Single | N |  | N | 449 | 449 | IR38064MTRP=GZS |  | IC,Regulator,IR38064MTRP=GZS ,ADJ,35A,G,QFN-26,SMD | INTERNATIONAL RECTIFIER | IR38064MTRP=GZS | 2 | G | PBNU1,PANU1 |  |  |  |  |  |  |
| Multi | N | ND | N | 450 | 450 | 340805A00-638-G |  | CONN,Switch,tact,50mA,12V,G,SMD-2 | E-SWITCH | TL1015AF160QG | 2 | G | SW1,SW2 |  |  |  |  |  |  |
|  |  |  |  |  | 450 | 340812T00-653-G |  | CONN,Switch,tact,50mA,12V,Bla,G,SMD-2 | DIPTRONICS MANUFACTURING INC. | MPTLP2-V-T/R |  | G |  |  |  |  |  |  |  |
| Single | ND |  | N | 451 | 451 | 34081GH00-653-G |  | CONN,Switch,tact,Brown,50mA,12V,G,DIP-4 | DIPTRONICS MANUFACTURING INC. | DTSA-644N-Q | 2 | G | SW3,SW4 |  |  |  |  |  |  |
| Single |  |  |  | 452 | 452 | 340109B00-600-G |  | POWER9 CPU Socket for LGA3899-HYBRID | FOXCONN TECHNOLOGY CO.,LTD. | PE38993-51BC1-1H | 2 | G | U1,U10 |  |  |  |  |  |  |
| Single | ND |  | Y(1) | 453 | 453 | UCD90160RGCR-C13 |  | IC,Power Controller,UCD90160RGCR,G,VQFN-64,SMD | TEXAS INSTRUMENTS | UCD90160RGCR-C13 | 1 | G | U5 |  |  |  |  |  |  |
| Single | ND | ND | N | 454 | 454 | 34061E400-GRS-G | - | CONN,Socket,SPI Flash,V/T,Bla,1.27mm,G/F,G,SMD-16 | LOTES CO LTD | ACA-SPI-006-F01 | 2 | G | U22,U23 |  |  |  |  |  |  |
